FILE_TYPE = MACRO_DRAWING;
SET COLOR_WIRE YELLOW;
SET COLOR_PROP ORANGE;
SET COLOR_DOT WHITE;
SET COLOR_ARC YELLOW;
SET COLOR_BODY GREEN;
SET COLOR_NOTE PURPLE;
SET PROP_DISPLAY VALUE;
SET PAGE_NUMBER P338;
FORCEADD UNIVERSAL_GND..1
(5950 8175);
FORCEPROP 3 LASTPIN (5950 8225) SIG_NAME GND\g
J 0
(5960 8235);
DISPLAY 0.659574 (5960 8235);
PAINT MONO (5960 8235);
DISPLAY INVISIBLE (5960 8235);
FORCEPROP 2 LAST CDS_LIB pure_quanta_power
J 0
(5950 8175);
PAINT MONO (5950 8175);
DISPLAY INVISIBLE (5950 8175);
FORCEPROP 1 LAST HDL_POWER GND
J 1
(5975 8100);
DISPLAY 0.872340 (5975 8100);
PAINT GREEN (5975 8100);
DISPLAY INVISIBLE (5975 8100);
FORCEPROP 1 LAST PATH I1
J 0
(6025 8175);
DISPLAY 0.872340 (6025 8175);
PAINT AQUA (6025 8175);
DISPLAY INVISIBLE (6025 8175);
FORCEADD UNIVERSAL_POWER..1
(3900 9150);
FORCEPROP 3 LASTPIN (3900 9100) SIG_NAME P3V3_AUX\g
J 0
(3910 9110);
DISPLAY 0.659574 (3910 9110);
PAINT MONO (3910 9110);
DISPLAY INVISIBLE (3910 9110);
FORCEPROP 1 LAST HDL_POWER P3V3_AUX
J 1
(3900 9200);
DISPLAY 0.872340 (3900 9200);
PAINT GREEN (3900 9200);
FORCEPROP 2 LAST CDS_LIB pure_quanta_power
J 0
(3900 9150);
DISPLAY INVISIBLE (3900 9150);
FORCEPROP 1 LAST PATH I10
J 0
(3950 9175);
DISPLAY 0.872340 (3950 9175);
PAINT AQUA (3950 9175);
DISPLAY INVISIBLE (3950 9175);
FORCEADD Q_CAP..1
R 1
(9275 12875);
FORCEPROP 1 LAST LOCATION PC2089
J 0
(9050 12875);
DISPLAY 0.638298 (9050 12875);
FORCEPROP 0 LAST $SEC 1
R 1
J 0
(9375 13000);
DISPLAY 0.680851 (9375 13000);
PAINT MONO (9375 13000);
DISPLAY INVISIBLE (9375 13000);
FORCEPROP 0 LAST CDS_SEC 1
R 1
J 0
(9375 13000);
DISPLAY 1.021277 (9375 13000);
DISPLAY INVISIBLE (9375 13000);
FORCEPROP 1 LASTPIN (9175 12875) $PN 1
R 1
J 0
(9195 12885);
DISPLAY 0.787234 (9195 12885);
PAINT MONO (9195 12885);
DISPLAY INVISIBLE (9195 12885);
FORCEPROP 1 LASTPIN (9375 12875) $PN 2
R 1
J 0
(9395 12885);
DISPLAY 0.787234 (9395 12885);
PAINT MONO (9395 12885);
DISPLAY INVISIBLE (9395 12885);
FORCEPROP 1 LAST VOLTAGE 50V
J 0
(9375 12925);
DISPLAY 0.638298 (9375 12925);
FORCEPROP 0 LAST ROOM NIC_P3V3_BOM1
J 0
(9100 12975);
DISPLAY 0.553191 (9100 12975);
PAINT RED (9100 12975);
FORCEPROP 1 LAST VALUE 6800PF
J 0
(9175 12925);
DISPLAY 0.638298 (9175 12925);
FORCEPROP 1 LAST PACK_TYPE C0402
J 0
(9050 12825);
DISPLAY 0.638298 (9050 12825);
FORCEPROP 2 LAST CDS_LIB pure_quanta
R 1
J 0
(9275 12875);
DISPLAY INVISIBLE (9275 12875);
FORCEPROP 1 LAST MATERIAL X7R
R 1
J 0
(9275 12925);
DISPLAY 0.638298 (9275 12925);
DISPLAY INVISIBLE (9275 12925);
FORCEPROP 1 LAST TOLERANCE 10%
R 1
J 0
(9325 12925);
DISPLAY 0.638298 (9325 12925);
DISPLAY INVISIBLE (9325 12925);
FORCEPROP 1 LAST PATH I100
R 1
J 0
(9125 12925);
DISPLAY 0.978723 (9125 12925);
PAINT WHITE (9125 12925);
DISPLAY INVISIBLE (9125 12925);
FORCEPROP 1 LAST PART_NUMBER CH2686K1B01
J 0
(9325 12875);
DISPLAY 0.638298 (9325 12875);
DISPLAY INVISIBLE (9325 12875);
FORCEADD Q_RES..2
(9675 13050);
FORCEPROP 1 LAST LOCATION R3796
J 0
(9725 13025);
DISPLAY 0.638298 (9725 13025);
FORCEPROP 0 LAST $SEC 1
J 0
(9725 13225);
DISPLAY 0.680851 (9725 13225);
PAINT MONO (9725 13225);
DISPLAY INVISIBLE (9725 13225);
FORCEPROP 0 LAST CDS_SEC 1
J 0
(9725 13225);
DISPLAY 1.021277 (9725 13225);
DISPLAY INVISIBLE (9725 13225);
FORCEPROP 1 LASTPIN (9675 13150) $PN 1
J 0
(9680 13112);
DISPLAY 0.787234 (9680 13112);
PAINT MONO (9680 13112);
FORCEPROP 1 LASTPIN (9675 12950) $PN 2
J 0
(9680 12960);
DISPLAY 0.787234 (9680 12960);
PAINT MONO (9680 12960);
FORCEPROP 1 LAST MATERIAL CHIP
J 0
(9725 12925);
DISPLAY 0.510638 (9725 12925);
FORCEPROP 1 LAST TOLERANCE 1%
J 0
(9725 12975);
DISPLAY 0.510638 (9725 12975);
FORCEPROP 0 LAST ROOM NIC_P3V3_BOM1
J 0
(9725 13075);
DISPLAY 0.553191 (9725 13075);
PAINT RED (9725 13075);
FORCEPROP 1 LAST VALUE 100K
J 0
(9725 13000);
DISPLAY 0.510638 (9725 13000);
FORCEPROP 1 LAST WATTAGE 1/16W
J 0
(9725 12950);
DISPLAY 0.510638 (9725 12950);
FORCEPROP 1 LAST PACK_TYPE 0402LF
J 0
(9725 12875);
DISPLAY 0.510638 (9725 12875);
FORCEPROP 2 LAST CDS_LIB pure_quanta
J 0
(9675 13050);
DISPLAY INVISIBLE (9675 13050);
FORCEPROP 1 LAST PATH I101
J 0
(9725 13225);
DISPLAY 0.978723 (9725 13225);
PAINT WHITE (9725 13225);
DISPLAY INVISIBLE (9725 13225);
FORCEPROP 1 LAST PART_NUMBER CS41002FB09
J 0
(9725 12900);
DISPLAY 0.510638 (9725 12900);
DISPLAY INVISIBLE (9725 12900);
FORCEADD VCCAUX15..1
(9875 13325);
FORCEPROP 3 LASTPIN (9875 13275) SIG_NAME P3V3_AUX\g
J 0
(9885 13285);
DISPLAY 0.659574 (9885 13285);
PAINT MONO (9885 13285);
DISPLAY INVISIBLE (9885 13285);
FORCEPROP 1 LAST HDL_POWER P3V3_AUX
J 1
(9875 13375);
DISPLAY 0.723404 (9875 13375);
PAINT GREEN (9875 13375);
FORCEPROP 2 LAST CDS_LIB pure_quanta_power
J 0
(9875 13325);
DISPLAY INVISIBLE (9875 13325);
FORCEPROP 1 LAST PATH I102
J 0
(9925 13350);
DISPLAY 0.872340 (9925 13350);
PAINT AQUA (9925 13350);
DISPLAY INVISIBLE (9925 13350);
FORCEADD Q_CAP..1
(9550 13650);
FORCEPROP 1 LAST LOCATION PC2091
J 0
(9600 13750);
DISPLAY 0.638298 (9600 13750);
FORCEPROP 0 LAST $SEC 1
J 0
(9600 13800);
DISPLAY 0.680851 (9600 13800);
PAINT MONO (9600 13800);
DISPLAY INVISIBLE (9600 13800);
FORCEPROP 0 LAST CDS_SEC 1
J 0
(9600 13800);
DISPLAY 1.021277 (9600 13800);
DISPLAY INVISIBLE (9600 13800);
FORCEPROP 1 LASTPIN (9550 13750) $PN 1
J 0
(9560 13730);
DISPLAY 0.787234 (9560 13730);
PAINT MONO (9560 13730);
DISPLAY INVISIBLE (9560 13730);
FORCEPROP 1 LASTPIN (9550 13550) $PN 2
J 0
(9560 13530);
DISPLAY 0.787234 (9560 13530);
PAINT MONO (9560 13530);
DISPLAY INVISIBLE (9560 13530);
FORCEPROP 1 LAST PACK_TYPE 0402
J 0
(9600 13550);
DISPLAY 0.638298 (9600 13550);
FORCEPROP 1 LAST VOLTAGE 25V
J 0
(9600 13650);
DISPLAY 0.638298 (9600 13650);
FORCEPROP 1 LAST MATERIAL X7R
J 0
(9600 13600);
DISPLAY 0.638298 (9600 13600);
FORCEPROP 1 LAST VALUE 0.1UF
J 0
(9600 13700);
DISPLAY 0.638298 (9600 13700);
FORCEPROP 1 LAST TOLERANCE 10%
J 0
(9600 13600);
DISPLAY 0.978723 (9600 13600);
DISPLAY INVISIBLE (9600 13600);
FORCEPROP 2 LAST CDS_LIB pure_quanta
J 0
(9550 13650);
DISPLAY INVISIBLE (9550 13650);
FORCEPROP 1 LAST PATH I104
J 0
(9600 13800);
DISPLAY 0.978723 (9600 13800);
PAINT WHITE (9600 13800);
DISPLAY INVISIBLE (9600 13800);
FORCEPROP 1 LAST PART_NUMBER CH4104K1B00
J 0
(9600 13500);
DISPLAY 0.638298 (9600 13500);
DISPLAY INVISIBLE (9600 13500);
FORCEADD GND..1
(10125 13350);
FORCEPROP 3 LASTPIN (10125 13400) SIG_NAME GND\g
J 0
(10135 13410);
DISPLAY 0.659574 (10135 13410);
PAINT MONO (10135 13410);
DISPLAY INVISIBLE (10135 13410);
FORCEPROP 1 LAST SIZE 1B
J 0
(10200 13300);
DISPLAY 0.872340 (10200 13300);
PAINT GREEN (10200 13300);
DISPLAY INVISIBLE (10200 13300);
FORCEPROP 2 LAST CDS_LIB pure_quanta_power
J 0
(10125 13350);
DISPLAY INVISIBLE (10125 13350);
FORCEPROP 1 LAST HDL_POWER GND
J 0
(10125 13500);
DISPLAY 0.872340 (10125 13500);
PAINT GREEN (10125 13500);
DISPLAY INVISIBLE (10125 13500);
FORCEPROP 1 LAST PATH I105
J 0
(10200 13350);
DISPLAY 0.872340 (10200 13350);
PAINT AQUA (10200 13350);
DISPLAY INVISIBLE (10200 13350);
FORCEADD Q_CAP..1
(10125 13650);
FORCEPROP 1 LAST LOCATION PC2081
J 0
(10175 13750);
DISPLAY 0.680851 (10175 13750);
FORCEPROP 0 LAST $SEC 1
J 0
(10175 13800);
DISPLAY INVISIBLE (10175 13800);
FORCEPROP 0 LAST CDS_SEC 1
J 0
(10175 13800);
DISPLAY INVISIBLE (10175 13800);
FORCEPROP 1 LASTPIN (10125 13750) $PN 1
J 0
(10135 13730);
DISPLAY 0.787234 (10135 13730);
PAINT MONO (10135 13730);
DISPLAY INVISIBLE (10135 13730);
FORCEPROP 1 LASTPIN (10125 13550) $PN 2
J 0
(10135 13530);
DISPLAY 0.787234 (10135 13530);
PAINT MONO (10135 13530);
DISPLAY INVISIBLE (10135 13530);
FORCEPROP 1 LAST PACK_TYPE C0805
J 0
(10175 13550);
DISPLAY 0.638298 (10175 13550);
FORCEPROP 1 LAST MATERIAL X6S
J 0
(10175 13600);
DISPLAY 0.638298 (10175 13600);
FORCEPROP 1 LAST VALUE 10UF
J 0
(10175 13700);
DISPLAY 0.638298 (10175 13700);
FORCEPROP 1 LAST VOLTAGE 16V
J 0
(10175 13650);
DISPLAY 0.638298 (10175 13650);
FORCEPROP 1 LAST TOLERANCE 10%
J 0
(9914 13610);
DISPLAY 0.787234 (9914 13610);
PAINT GREEN (9914 13610);
DISPLAY INVISIBLE (9914 13610);
FORCEPROP 2 LAST CDS_LIB pure_quanta
J 0
(10125 13650);
DISPLAY INVISIBLE (10125 13650);
FORCEPROP 1 LAST PATH I106
J 0
(10175 13800);
DISPLAY 0.978723 (10175 13800);
PAINT WHITE (10175 13800);
DISPLAY INVISIBLE (10175 13800);
FORCEPROP 1 LAST PART_NUMBER CH6103KEA01
J 0
(10175 13500);
DISPLAY 0.638298 (10175 13500);
DISPLAY INVISIBLE (10175 13500);
FORCEADD UNIVERSAL_POWER..1
R 2
(10125 13950);
FORCEPROP 3 LASTPIN (10125 13900) SIG_NAME P3V3_OCP_SFF_R\g
J 0
(10135 13910);
DISPLAY 0.659574 (10135 13910);
PAINT MONO (10135 13910);
DISPLAY INVISIBLE (10135 13910);
FORCEPROP 1 LAST HDL_POWER P3V3_OCP_SFF_R
J 1
(10125 14000);
DISPLAY 0.723404 (10125 14000);
PAINT GREEN (10125 14000);
FORCEPROP 2 LAST CDS_LIB pure_quanta_power
J 0
(10125 13950);
DISPLAY INVISIBLE (10125 13950);
FORCEPROP 1 LAST PATH I107
J 2
(10075 13975);
DISPLAY 0.872340 (10075 13975);
PAINT AQUA (10075 13975);
DISPLAY INVISIBLE (10075 13975);
FORCEADD OFFPAGE..2
(10375 12775);
PAINT AQUA (10375 12775);
FORCEPROP 2 LAST $XR0 136 
J 0
(10564 12775);
DISPLAY 0.638298 (10564 12775);
PAINT MONO (10564 12775);
FORCEPROP 2 LAST CDS_LIB standard
J 0
(10375 12775);
DISPLAY INVISIBLE (10375 12775);
FORCEPROP 1 LAST OFFPAGE TRUE
J 0
(10700 12650);
DISPLAY 0.872340 (10700 12650);
PAINT AQUA (10700 12650);
DISPLAY INVISIBLE (10700 12650);
FORCEPROP 1 LAST COMMENT_BODY TRUE
J 0
(10330 12680);
DISPLAY 0.872340 (10330 12680);
PAINT GREEN (10330 12680);
DISPLAY INVISIBLE (10330 12680);
FORCEPROP 2 LAST PATH I108
J 0
(10575 12825);
DISPLAY 0.680851 (10575 12825);
DISPLAY INVISIBLE (10575 12825);
FORCEADD GND..1
(5900 13225);
FORCEPROP 3 LASTPIN (5900 13275) SIG_NAME GND\g
J 0
(5910 13285);
DISPLAY 0.659574 (5910 13285);
PAINT MONO (5910 13285);
DISPLAY INVISIBLE (5910 13285);
FORCEPROP 1 LAST SIZE 1B
J 0
(5975 13175);
DISPLAY 0.872340 (5975 13175);
PAINT GREEN (5975 13175);
DISPLAY INVISIBLE (5975 13175);
FORCEPROP 2 LAST CDS_LIB pure_quanta_power
J 0
(5900 13225);
DISPLAY INVISIBLE (5900 13225);
FORCEPROP 1 LAST HDL_POWER GND
J 0
(5900 13375);
DISPLAY 0.872340 (5900 13375);
PAINT GREEN (5900 13375);
DISPLAY INVISIBLE (5900 13375);
FORCEPROP 1 LAST PATH I109
J 0
(5975 13225);
DISPLAY 0.872340 (5975 13225);
PAINT AQUA (5975 13225);
DISPLAY INVISIBLE (5975 13225);
FORCEADD MOSFET_NCH_DUAL..1
(3575 10275);
FORCEPROP 1 LAST LOCATION Q123
J 0
(3726 10249);
DISPLAY 0.723404 (3726 10249);
PAINT GREEN (3726 10249);
FORCEPROP 0 LAST $SEC 1
J 0
(3750 10400);
DISPLAY 0.680851 (3750 10400);
PAINT MONO (3750 10400);
DISPLAY INVISIBLE (3750 10400);
FORCEPROP 0 LAST CDS_SEC 1
J 0
(3750 10400);
DISPLAY 1.021277 (3750 10400);
DISPLAY INVISIBLE (3750 10400);
FORCEPROP 0 LASTPIN (3625 10475) $PN 6
R 1
J 0
(3615 10485);
DISPLAY 0.680851 (3615 10485);
PAINT MONO (3615 10485);
FORCEPROP 0 LASTPIN (3375 10225) $PN 2
J 2
(3365 10235);
DISPLAY 0.680851 (3365 10235);
PAINT MONO (3365 10235);
FORCEPROP 0 LASTPIN (3625 10075) $PN 1
R 1
J 2
(3615 10065);
DISPLAY 0.680851 (3615 10065);
PAINT MONO (3615 10065);
FORCEPROP 2 LAST PART_TYPE SMLF
J 0
(3750 10350);
DISPLAY 1.021277 (3750 10350);
FORCEPROP 1 LAST MATERIAL IC
J 0
(3726 10124);
DISPLAY 0.723404 (3726 10124);
PAINT GREEN (3726 10124);
FORCEPROP 2 LAST VALUE PJT138K
J 0
(3750 10300);
DISPLAY 1.021277 (3750 10300);
FORCEPROP 0 LAST ROOM NIC_P12V_MAM_TIC_BOM1
J 0
(3750 10425);
DISPLAY 0.553191 (3750 10425);
PAINT RED (3750 10425);
FORCEPROP 1 LAST NEEDS_NO_SIZE TRUE
J 0
(3575 10274);
DISPLAY 0.468085 (3575 10274);
PAINT GREEN (3575 10274);
DISPLAY INVISIBLE (3575 10274);
FORCEPROP 1 LAST CDS_LMAN_SYM_OUTLINE -150,150,150,-150
J 0
(3575 10275);
DISPLAY 0.468085 (3575 10275);
PAINT GREEN (3575 10275);
DISPLAY INVISIBLE (3575 10275);
FORCEPROP 2 LAST CDS_LIB pure_quanta
J 0
(3575 10275);
DISPLAY INVISIBLE (3575 10275);
FORCEPROP 1 LAST PATH I11
J 0
(3575 10275);
DISPLAY 0.723404 (3575 10275);
PAINT GREEN (3575 10275);
DISPLAY INVISIBLE (3575 10275);
FORCEPROP 1 LAST PART_NUMBER BAM138K0003
J 0
(3726 10189);
DISPLAY 0.723404 (3726 10189);
PAINT GREEN (3726 10189);
DISPLAY INVISIBLE (3726 10189);
FORCEADD Q_CAP..1
(6575 13075);
FORCEPROP 1 LAST LOCATION PC2086
J 0
(6625 13100);
DISPLAY 0.638298 (6625 13100);
FORCEPROP 0 LAST $SEC 1
J 0
(6625 13150);
DISPLAY 0.680851 (6625 13150);
PAINT MONO (6625 13150);
DISPLAY INVISIBLE (6625 13150);
FORCEPROP 0 LAST CDS_SEC 1
J 0
(6625 13150);
DISPLAY 1.021277 (6625 13150);
DISPLAY INVISIBLE (6625 13150);
FORCEPROP 1 LASTPIN (6575 13175) $PN 1
J 0
(6585 13155);
DISPLAY 0.787234 (6585 13155);
PAINT MONO (6585 13155);
DISPLAY INVISIBLE (6585 13155);
FORCEPROP 1 LASTPIN (6575 12975) $PN 2
J 0
(6585 12955);
DISPLAY 0.787234 (6585 12955);
PAINT MONO (6585 12955);
DISPLAY INVISIBLE (6585 12955);
FORCEPROP 0 LAST ROOM NIC_P3V3_BOM1
J 0
(6625 13175);
DISPLAY 0.446809 (6625 13175);
PAINT RED (6625 13175);
FORCEPROP 1 LAST VALUE 1UF
J 0
(6625 13075);
DISPLAY 0.510638 (6625 13075);
FORCEPROP 1 LAST MATERIAL X6S
J 0
(6625 13050);
DISPLAY 0.510638 (6625 13050);
FORCEPROP 1 LAST VOLTAGE 25V
J 0
(6625 13025);
DISPLAY 0.510638 (6625 13025);
FORCEPROP 1 LAST PACK_TYPE C0402
J 0
(6625 13000);
DISPLAY 0.510638 (6625 13000);
FORCEPROP 2 LAST CDS_LIB pure_quanta
J 0
(6575 13075);
DISPLAY INVISIBLE (6575 13075);
FORCEPROP 1 LAST TOLERANCE 10%
J 0
(6625 13025);
DISPLAY 0.638298 (6625 13025);
DISPLAY INVISIBLE (6625 13025);
FORCEPROP 1 LAST PATH I110
J 0
(6625 13225);
DISPLAY 0.978723 (6625 13225);
PAINT WHITE (6625 13225);
DISPLAY INVISIBLE (6625 13225);
FORCEPROP 1 LAST PART_NUMBER CH5104KEB02
J 0
(6625 12975);
DISPLAY 0.510638 (6625 12975);
DISPLAY INVISIBLE (6625 12975);
FORCEADD Q_RES..2
(7100 12275);
FORCEPROP 1 LAST LOCATION PR3780
J 0
(7150 12325);
DISPLAY 0.638298 (7150 12325);
FORCEPROP 0 LAST $SEC 1
J 0
(7150 12425);
DISPLAY 0.680851 (7150 12425);
PAINT MONO (7150 12425);
DISPLAY INVISIBLE (7150 12425);
FORCEPROP 0 LAST CDS_SEC 1
J 0
(7150 12400);
DISPLAY INVISIBLE (7150 12400);
FORCEPROP 1 LASTPIN (7100 12375) $PN 1
J 0
(7105 12337);
DISPLAY 0.787234 (7105 12337);
PAINT MONO (7105 12337);
FORCEPROP 1 LASTPIN (7100 12175) $PN 2
J 0
(7105 12185);
DISPLAY 0.787234 (7105 12185);
PAINT MONO (7105 12185);
FORCEPROP 1 LAST MATERIAL CHIP
J 0
(7150 12225);
DISPLAY 0.510638 (7150 12225);
FORCEPROP 1 LAST PACK_TYPE 0402LF
J 0
(7150 12175);
DISPLAY 0.510638 (7150 12175);
FORCEPROP 1 LAST WATTAGE 1/16W
J 0
(7150 12250);
DISPLAY 0.510638 (7150 12250);
FORCEPROP 1 LAST TOLERANCE 1%
J 0
(7150 12275);
DISPLAY 0.510638 (7150 12275);
FORCEPROP 1 LAST VALUE 5.36K
J 0
(7150 12300);
DISPLAY 0.510638 (7150 12300);
FORCEPROP 0 LAST ROOM NIC_P3V3_BOM1
J 0
(7150 12125);
DISPLAY 0.553191 (7150 12125);
PAINT RED (7150 12125);
FORCEPROP 2 LAST CDS_LIB pure_quanta
J 0
(7100 12275);
DISPLAY INVISIBLE (7100 12275);
FORCEPROP 1 LAST PATH I111
J 0
(7150 12450);
DISPLAY 0.978723 (7150 12450);
PAINT WHITE (7150 12450);
DISPLAY INVISIBLE (7150 12450);
FORCEPROP 1 LAST PART_NUMBER CS25362FB02
J 0
(7150 12200);
DISPLAY 0.510638 (7150 12200);
DISPLAY INVISIBLE (7150 12200);
FORCEADD MOSFET_NCH_DUAL..2
(4925 12250);
FORCEPROP 1 LAST LOCATION Q124
J 0
(5076 12226);
DISPLAY 0.723404 (5076 12226);
PAINT GREEN (5076 12226);
FORCEPROP 0 LAST $SEC 2
J 0
(5100 12375);
DISPLAY 0.680851 (5100 12375);
PAINT MONO (5100 12375);
DISPLAY INVISIBLE (5100 12375);
FORCEPROP 0 LAST CDS_SEC 2
J 0
(5100 12375);
DISPLAY 1.021277 (5100 12375);
DISPLAY INVISIBLE (5100 12375);
FORCEPROP 0 LASTPIN (4975 12450) $PN 3
R 1
J 0
(4965 12460);
DISPLAY 0.680851 (4965 12460);
PAINT MONO (4965 12460);
FORCEPROP 0 LASTPIN (4725 12200) $PN 5
J 2
(4715 12210);
DISPLAY 0.680851 (4715 12210);
PAINT MONO (4715 12210);
FORCEPROP 0 LASTPIN (4975 12050) $PN 4
R 1
J 2
(4965 12040);
DISPLAY 0.680851 (4965 12040);
PAINT MONO (4965 12040);
FORCEPROP 2 LAST PART_TYPE SMLF
J 0
(5100 12325);
DISPLAY 1.021277 (5100 12325);
FORCEPROP 0 LAST ROOM NIC_P3V3_BOM1
J 0
(5100 12425);
DISPLAY 0.680851 (5100 12425);
PAINT RED (5100 12425);
FORCEPROP 1 LAST MATERIAL IC
J 0
(5076 12101);
DISPLAY 0.723404 (5076 12101);
PAINT GREEN (5076 12101);
FORCEPROP 2 LAST VALUE PJT138K
J 0
(5100 12275);
DISPLAY 1.021277 (5100 12275);
FORCEPROP 2 LAST CDS_LIB pure_quanta
J 0
(4925 12250);
DISPLAY INVISIBLE (4925 12250);
FORCEPROP 1 LAST CDS_LMAN_SYM_OUTLINE -150,150,150,-150
J 0
(4925 12250);
DISPLAY 0.468085 (4925 12250);
PAINT GREEN (4925 12250);
DISPLAY INVISIBLE (4925 12250);
FORCEPROP 1 LAST NEEDS_NO_SIZE TRUE
J 0
(5075 12141);
DISPLAY 0.468085 (5075 12141);
PAINT GREEN (5075 12141);
DISPLAY INVISIBLE (5075 12141);
FORCEPROP 1 LAST PATH I112
J 0
(5075 12100);
DISPLAY 0.723404 (5075 12100);
PAINT GREEN (5075 12100);
DISPLAY INVISIBLE (5075 12100);
FORCEPROP 1 LAST PART_NUMBER BAM138K0003
J 0
(5076 12156);
DISPLAY 0.723404 (5076 12156);
PAINT GREEN (5076 12156);
DISPLAY INVISIBLE (5076 12156);
FORCEADD MAX15090BEWIT..1
(7850 12775);
FORCEPROP 1 LAST LOCATION PU202
J 0
(7597 13503);
DISPLAY 0.723404 (7597 13503);
PAINT GREEN (7597 13503);
FORCEPROP 0 LAST $SEC 1
J 0
(7600 13650);
DISPLAY 0.680851 (7600 13650);
PAINT MONO (7600 13650);
DISPLAY INVISIBLE (7600 13650);
FORCEPROP 0 LAST CDS_SEC 1
J 0
(7600 13650);
DISPLAY 1.021277 (7600 13650);
DISPLAY INVISIBLE (7600 13650);
FORCEPROP 0 LASTPIN (7450 12475) $PN B1
J 2
(7440 12485);
DISPLAY 0.680851 (7440 12485);
PAINT MONO (7440 12485);
FORCEPROP 0 LASTPIN (8250 12475) $PN A7
J 0
(8260 12485);
DISPLAY 0.680851 (8260 12485);
PAINT MONO (8260 12485);
FORCEPROP 0 LASTPIN (7450 12375) $PN B7
J 2
(7440 12385);
DISPLAY 0.680851 (7440 12385);
PAINT MONO (7440 12385);
FORCEPROP 0 LASTPIN (8250 12675) $PN C7
J 0
(8260 12685);
DISPLAY 0.680851 (8260 12685);
PAINT MONO (8260 12685);
FORCEPROP 0 LASTPIN (8250 12875) $PN A6
J 0
(8260 12885);
DISPLAY 0.680851 (8260 12885);
PAINT MONO (8260 12885);
FORCEPROP 0 LASTPIN (8250 12375) $PN B2
J 0
(8260 12385);
DISPLAY 0.680851 (8260 12385);
PAINT MONO (8260 12385);
FORCEPROP 0 LASTPIN (8250 12325) $PN C1
J 0
(8260 12335);
DISPLAY 0.680851 (8260 12335);
PAINT MONO (8260 12335);
FORCEPROP 0 LASTPIN (8250 12275) $PN C2
J 0
(8260 12285);
DISPLAY 0.680851 (8260 12285);
PAINT MONO (8260 12285);
FORCEPROP 0 LASTPIN (7450 13275) $PN A3
J 2
(7440 13285);
DISPLAY 0.680851 (7440 13285);
PAINT MONO (7440 13285);
FORCEPROP 0 LASTPIN (7450 13225) $PN A5
J 2
(7440 13235);
DISPLAY 0.680851 (7440 13235);
PAINT MONO (7440 13235);
FORCEPROP 0 LASTPIN (7450 13175) $PN B3
J 2
(7440 13185);
DISPLAY 0.680851 (7440 13185);
PAINT MONO (7440 13185);
FORCEPROP 0 LASTPIN (7450 13125) $PN B5
J 2
(7440 13135);
DISPLAY 0.680851 (7440 13135);
PAINT MONO (7440 13135);
FORCEPROP 0 LASTPIN (7450 13075) $PN C3
J 2
(7440 13085);
DISPLAY 0.680851 (7440 13085);
PAINT MONO (7440 13085);
FORCEPROP 0 LASTPIN (7450 13025) $PN C5
J 2
(7440 13035);
DISPLAY 0.680851 (7440 13035);
PAINT MONO (7440 13035);
FORCEPROP 0 LASTPIN (7450 12975) $PN D5
J 2
(7440 12985);
DISPLAY 0.680851 (7440 12985);
PAINT MONO (7440 12985);
FORCEPROP 0 LASTPIN (8250 12575) $PN A1
J 0
(8260 12585);
DISPLAY 0.680851 (8260 12585);
PAINT MONO (8260 12585);
FORCEPROP 0 LASTPIN (8250 13275) $PN A4
J 0
(8260 13285);
DISPLAY 0.680851 (8260 13285);
PAINT MONO (8260 13285);
FORCEPROP 0 LASTPIN (8250 13225) $PN B4
J 0
(8260 13235);
DISPLAY 0.680851 (8260 13235);
PAINT MONO (8260 13235);
FORCEPROP 0 LASTPIN (8250 13175) $PN B6
J 0
(8260 13185);
DISPLAY 0.680851 (8260 13185);
PAINT MONO (8260 13185);
FORCEPROP 0 LASTPIN (8250 13125) $PN C4
J 0
(8260 13135);
DISPLAY 0.680851 (8260 13135);
PAINT MONO (8260 13135);
FORCEPROP 0 LASTPIN (8250 13075) $PN C6
J 0
(8260 13085);
DISPLAY 0.680851 (8260 13085);
PAINT MONO (8260 13085);
FORCEPROP 0 LASTPIN (8250 13025) $PN D4
J 0
(8260 13035);
DISPLAY 0.680851 (8260 13035);
PAINT MONO (8260 13035);
FORCEPROP 0 LASTPIN (8250 12975) $PN D6
J 0
(8260 12985);
DISPLAY 0.680851 (8260 12985);
PAINT MONO (8260 12985);
FORCEPROP 0 LASTPIN (7450 12575) $PN D3
J 2
(7440 12585);
DISPLAY 0.680851 (7440 12585);
PAINT MONO (7440 12585);
FORCEPROP 0 LASTPIN (8250 12775) $PN D7
J 0
(8260 12785);
DISPLAY 0.680851 (8260 12785);
PAINT MONO (8260 12785);
FORCEPROP 0 LASTPIN (7450 12775) $PN D1
J 2
(7440 12785);
DISPLAY 0.680851 (7440 12785);
PAINT MONO (7440 12785);
FORCEPROP 0 LASTPIN (7450 12675) $PN D2
J 2
(7440 12685);
DISPLAY 0.680851 (7440 12685);
PAINT MONO (7440 12685);
FORCEPROP 0 LASTPIN (7450 12875) $PN A2
J 2
(7440 12885);
DISPLAY 0.680851 (7440 12885);
PAINT MONO (7440 12885);
FORCEPROP 0 LAST ROOM NIC_P3V3_BOM1
J 0
(7600 13700);
DISPLAY 0.680851 (7600 13700);
PAINT RED (7600 13700);
FORCEPROP 2 LAST PART_TYPE SMLF
J 0
(7600 13600);
DISPLAY 1.021277 (7600 13600);
FORCEPROP 2 LAST VALUE MAX15090BEWI+T
J 0
(7600 13550);
DISPLAY 1.021277 (7600 13550);
FORCEPROP 1 LAST MATERIAL IC
J 0
(7597 13330);
DISPLAY 0.723404 (7597 13330);
PAINT GREEN (7597 13330);
FORCEPROP 1 LAST CDS_LMAN_SYM_OUTLINE -250,550,250,-550
J 0
(7850 12775);
DISPLAY 0.468085 (7850 12775);
PAINT GREEN (7850 12775);
DISPLAY INVISIBLE (7850 12775);
FORCEPROP 1 LAST PIN_NAMES_ROTATE True
J 0
(7850 12775);
DISPLAY 0.489362 (7850 12775);
PAINT GREEN (7850 12775);
DISPLAY INVISIBLE (7850 12775);
FORCEPROP 2 LAST CDS_LIB pure_quanta
J 0
(7850 12775);
DISPLAY INVISIBLE (7850 12775);
FORCEPROP 1 LAST PATH I113
J 0
(8100 12225);
DISPLAY 0.723404 (8100 12225);
PAINT GREEN (8100 12225);
DISPLAY INVISIBLE (8100 12225);
FORCEPROP 1 LAST PART_NUMBER AL015080B00
J 0
(7597 13419);
DISPLAY 0.723404 (7597 13419);
PAINT GREEN (7597 13419);
DISPLAY INVISIBLE (7597 13419);
FORCEADD Q_RES..2
(6250 12250);
FORCEPROP 1 LAST LOCATION PR3791
J 0
(6300 12325);
DISPLAY 0.638298 (6300 12325);
FORCEPROP 0 LAST $SEC 1
J 0
(6300 12375);
DISPLAY 0.680851 (6300 12375);
PAINT MONO (6300 12375);
DISPLAY INVISIBLE (6300 12375);
FORCEPROP 0 LAST CDS_SEC 1
J 0
(6300 12375);
DISPLAY 1.021277 (6300 12375);
DISPLAY INVISIBLE (6300 12375);
FORCEPROP 1 LASTPIN (6250 12350) $PN 1
J 0
(6255 12312);
DISPLAY 0.787234 (6255 12312);
PAINT MONO (6255 12312);
DISPLAY INVISIBLE (6255 12312);
FORCEPROP 1 LASTPIN (6250 12150) $PN 2
J 0
(6255 12160);
DISPLAY 0.787234 (6255 12160);
PAINT MONO (6255 12160);
DISPLAY INVISIBLE (6255 12160);
FORCEPROP 0 LAST ROOM NIC_P3V3_BOM1
J 0
(6300 12150);
DISPLAY 0.446809 (6300 12150);
PAINT RED (6300 12150);
FORCEPROP 1 LAST TOLERANCE 1%
J 0
(6300 12275);
DISPLAY 0.404255 (6300 12275);
FORCEPROP 1 LAST WATTAGE 1/16W
J 0
(6300 12250);
DISPLAY 0.404255 (6300 12250);
FORCEPROP 1 LAST MATERIAL CHIP
J 0
(6300 12225);
DISPLAY 0.404255 (6300 12225);
FORCEPROP 1 LAST PACK_TYPE 0402LF
J 0
(6300 12175);
DISPLAY 0.404255 (6300 12175);
FORCEPROP 1 LAST VALUE 15K
J 0
(6300 12300);
DISPLAY 0.404255 (6300 12300);
FORCEPROP 2 LAST CDS_LIB pure_quanta
J 0
(6250 12250);
DISPLAY INVISIBLE (6250 12250);
FORCEPROP 1 LAST PATH I114
J 0
(6300 12425);
DISPLAY 0.978723 (6300 12425);
PAINT WHITE (6300 12425);
DISPLAY INVISIBLE (6300 12425);
FORCEPROP 1 LAST PART_NUMBER CS31502FB05
J 0
(6300 12200);
DISPLAY 0.404255 (6300 12200);
DISPLAY INVISIBLE (6300 12200);
FORCEADD DIODE_TVS..1
R 1
(5300 11450);
FORCEPROP 1 LAST LOCATION PD101
J 0
(5355 11492);
DISPLAY 0.574468 (5355 11492);
PAINT GREEN (5355 11492);
FORCEPROP 0 LAST $SEC 1
R 1
J 0
(5355 11542);
DISPLAY INVISIBLE (5355 11542);
FORCEPROP 0 LAST CDS_SEC 1
R 1
J 0
(5355 11542);
DISPLAY INVISIBLE (5355 11542);
FORCEPROP 0 LASTPIN (5300 11300) $PN A
R 1
J 2
(5290 11290);
DISPLAY 0.808511 (5290 11290);
FORCEPROP 0 LASTPIN (5300 11600) $PN C
R 1
J 0
(5290 11610);
DISPLAY 0.808511 (5290 11610);
FORCEPROP 2 LAST VALUE SMF14A
J 0
(5350 11425);
DISPLAY 0.574468 (5350 11425);
PAINT SKYBLUE (5350 11425);
FORCEPROP 1 LAST MATERIAL IC
J 0
(5350 11300);
DISPLAY 0.723404 (5350 11300);
PAINT GREEN (5350 11300);
FORCEPROP 2 LAST CDS_LIB pure_quanta
J 0
(5300 11450);
DISPLAY INVISIBLE (5300 11450);
FORCEPROP 1 LAST CDS_LMAN_SYM_OUTLINE -100,50,100,-50
R 1
J 0
(5300 11450);
DISPLAY 0.468085 (5300 11450);
PAINT GREEN (5300 11450);
DISPLAY INVISIBLE (5300 11450);
FORCEPROP 1 LASTPIN (5300 11600) Pin_Length Short
R 1
J 0
(5310 11625);
DISPLAY 0.489362 (5310 11625);
PAINT MONO (5310 11625);
DISPLAY INVISIBLE (5310 11625);
FORCEPROP 0 LAST PART_TYPE SMLF
J 0
(5400 11575);
DISPLAY 1.021277 (5400 11575);
DISPLAY INVISIBLE (5400 11575);
FORCEPROP 1 LAST PIN_NAMES_ROTATE True
R 1
J 0
(5300 11450);
DISPLAY 0.489362 (5300 11450);
PAINT GREEN (5300 11450);
DISPLAY INVISIBLE (5300 11450);
FORCEPROP 1 LAST PATH I115
R 1
J 0
(5350 11550);
DISPLAY 0.723404 (5350 11550);
PAINT GREEN (5350 11550);
DISPLAY INVISIBLE (5350 11550);
FORCEPROP 1 LAST PART_NUMBER BCSMF14AZ01
J 0
(5355 11367);
DISPLAY 0.574468 (5355 11367);
PAINT GREEN (5355 11367);
DISPLAY INVISIBLE (5355 11367);
FORCEADD Q_RES..1
(6850 8675);
FORCEPROP 1 LAST LOCATION R576
J 0
(6650 8675);
DISPLAY 0.638298 (6650 8675);
FORCEPROP 0 LAST $SEC 1
J 0
(6650 8725);
DISPLAY 0.680851 (6650 8725);
PAINT MONO (6650 8725);
DISPLAY INVISIBLE (6650 8725);
FORCEPROP 0 LAST CDS_SEC 1
J 0
(6650 8725);
DISPLAY 0.680851 (6650 8725);
DISPLAY INVISIBLE (6650 8725);
FORCEPROP 1 LASTPIN (6750 8675) $PN 1
J 0
(6762 8687);
DISPLAY 0.787234 (6762 8687);
PAINT MONO (6762 8687);
FORCEPROP 1 LASTPIN (6950 8675) $PN 2
J 0
(6912 8687);
DISPLAY 0.787234 (6912 8687);
PAINT MONO (6912 8687);
FORCEPROP 1 LAST VALUE 0
J 2
(7000 8675);
DISPLAY 0.404255 (7000 8675);
FORCEPROP 1 LAST TOLERANCE 5%
J 0
(7025 8675);
DISPLAY 0.404255 (7025 8675);
FORCEPROP 1 LAST WATTAGE 1/16W
J 2
(6975 8600);
DISPLAY 0.404255 (6975 8600);
FORCEPROP 1 LAST PACK_TYPE 0402LF
J 0
(7075 8675);
DISPLAY 0.404255 (7075 8675);
FORCEPROP 1 LAST MATERIAL CHIP
J 0
(6775 8600);
DISPLAY 0.404255 (6775 8600);
FORCEPROP 2 LAST CDS_LIB pure_quanta
J 0
(6850 8675);
DISPLAY INVISIBLE (6850 8675);
FORCEPROP 1 LAST PATH I116
J 0
(6800 8825);
DISPLAY 0.978723 (6800 8825);
PAINT WHITE (6800 8825);
DISPLAY INVISIBLE (6800 8825);
FORCEPROP 1 LAST PART_NUMBER CS00002JB13
J 0
(6775 8625);
DISPLAY 0.404255 (6775 8625);
DISPLAY INVISIBLE (6775 8625);
FORCEADD OFFPAGE..2
(8475 8675);
FORCEPROP 2 LAST $XR0 136 
J 0
(8664 8675);
DISPLAY 0.638298 (8664 8675);
PAINT MONO (8664 8675);
FORCEPROP 2 LAST CDS_LIB standard
J 0
(8475 8675);
DISPLAY INVISIBLE (8475 8675);
FORCEPROP 1 LAST OFFPAGE TRUE
J 0
(8800 8550);
DISPLAY 0.872340 (8800 8550);
DISPLAY INVISIBLE (8800 8550);
FORCEPROP 1 LAST COMMENT_BODY TRUE
J 0
(8430 8580);
DISPLAY 0.872340 (8430 8580);
PAINT GREEN (8430 8580);
DISPLAY INVISIBLE (8430 8580);
FORCEPROP 2 LAST PATH I117
J 0
(8650 8750);
DISPLAY 0.680851 (8650 8750);
DISPLAY INVISIBLE (8650 8750);
FORCEADD Q_RES..2
R 2
(8200 9325);
FORCEPROP 1 LAST LOCATION R577
J 2
(8155 9450);
DISPLAY 0.978723 (8155 9450);
FORCEPROP 0 LAST $SEC 1
J 0
(8175 9500);
DISPLAY 0.680851 (8175 9500);
PAINT MONO (8175 9500);
DISPLAY INVISIBLE (8175 9500);
FORCEPROP 0 LAST CDS_SEC 1
J 0
(8175 9500);
DISPLAY 0.680851 (8175 9500);
DISPLAY INVISIBLE (8175 9500);
FORCEPROP 1 LASTPIN (8200 9425) $PN 1
J 2
(8195 9387);
DISPLAY 0.787234 (8195 9387);
PAINT MONO (8195 9387);
FORCEPROP 1 LASTPIN (8200 9225) $PN 2
J 2
(8195 9235);
DISPLAY 0.787234 (8195 9235);
PAINT MONO (8195 9235);
FORCEPROP 1 LAST PACK_TYPE 0402LF
J 2
(8160 9200);
DISPLAY 0.510638 (8160 9200);
FORCEPROP 1 LAST VALUE 10K
J 2
(8155 9400);
DISPLAY 0.510638 (8155 9400);
FORCEPROP 1 LAST MATERIAL CHIP
J 2
(8160 9250);
DISPLAY 0.510638 (8160 9250);
FORCEPROP 1 LAST WATTAGE 1/16W
J 2
(8160 9300);
DISPLAY 0.510638 (8160 9300);
FORCEPROP 1 LAST TOLERANCE 1%
J 2
(8155 9350);
DISPLAY 0.510638 (8155 9350);
FORCEPROP 2 LAST CDS_LIB pure_quanta
J 2
(8200 9325);
DISPLAY INVISIBLE (8200 9325);
FORCEPROP 1 LAST PATH I118
J 2
(8150 9500);
DISPLAY 0.978723 (8150 9500);
PAINT WHITE (8150 9500);
DISPLAY INVISIBLE (8150 9500);
FORCEPROP 1 LAST PART_NUMBER CS31002FB08
J 2
(8160 9150);
DISPLAY 0.510638 (8160 9150);
DISPLAY INVISIBLE (8160 9150);
FORCEADD GND..1
(3625 9925);
FORCEPROP 3 LASTPIN (3625 9975) SIG_NAME GND\g
J 0
(3635 9985);
DISPLAY 0.659574 (3635 9985);
PAINT MONO (3635 9985);
DISPLAY INVISIBLE (3635 9985);
FORCEPROP 2 LAST CDS_LIB pure_quanta_power
J 0
(3625 9925);
DISPLAY INVISIBLE (3625 9925);
FORCEPROP 1 LAST SIZE 1B
J 0
(3700 9875);
DISPLAY 0.872340 (3700 9875);
PAINT GREEN (3700 9875);
DISPLAY INVISIBLE (3700 9875);
FORCEPROP 1 LAST HDL_POWER GND
J 0
(3625 10075);
DISPLAY 0.872340 (3625 10075);
PAINT GREEN (3625 10075);
DISPLAY INVISIBLE (3625 10075);
FORCEPROP 1 LAST PATH I12
J 0
(3700 9925);
DISPLAY 0.872340 (3700 9925);
PAINT AQUA (3700 9925);
DISPLAY INVISIBLE (3700 9925);
FORCEADD Q_RES..1
(2600 10225);
FORCEPROP 1 LAST LOCATION R4061
J 0
(2550 10250);
DISPLAY 0.638298 (2550 10250);
FORCEPROP 0 LAST $SEC 1
J 0
(2550 10300);
DISPLAY 0.680851 (2550 10300);
PAINT MONO (2550 10300);
DISPLAY INVISIBLE (2550 10300);
FORCEPROP 0 LAST CDS_SEC 1
J 0
(2550 10300);
DISPLAY 0.680851 (2550 10300);
DISPLAY INVISIBLE (2550 10300);
FORCEPROP 1 LASTPIN (2500 10225) $PN 1
J 0
(2512 10237);
DISPLAY 0.787234 (2512 10237);
PAINT MONO (2512 10237);
FORCEPROP 1 LASTPIN (2700 10225) $PN 2
J 0
(2662 10237);
DISPLAY 0.787234 (2662 10237);
PAINT MONO (2662 10237);
FORCEPROP 1 LAST TOLERANCE 5%
J 0
(2775 10225);
DISPLAY 0.510638 (2775 10225);
FORCEPROP 1 LAST VALUE 0
J 2
(2750 10225);
DISPLAY 0.510638 (2750 10225);
FORCEPROP 0 LAST ROOM NIC_P12V_MAM_TIC_BOM1
J 0
(2325 10150);
DISPLAY 0.553191 (2325 10150);
PAINT RED (2325 10150);
FORCEPROP 1 LAST MATERIAL EMPTY
J 0
(2375 10225);
DISPLAY 0.510638 (2375 10225);
PAINT RED (2375 10225);
FORCEPROP 2 LAST CDS_LIB pure_quanta
J 0
(2600 10225);
DISPLAY INVISIBLE (2600 10225);
FORCEPROP 1 LAST PACK_TYPE 0402LF
J 0
(2850 10225);
DISPLAY 0.510638 (2850 10225);
DISPLAY INVISIBLE (2850 10225);
FORCEPROP 1 LAST WATTAGE 1/16W
J 2
(2700 10150);
DISPLAY 0.319149 (2700 10150);
DISPLAY INVISIBLE (2700 10150);
FORCEPROP 1 LAST PATH I123
J 0
(2550 10375);
DISPLAY 0.978723 (2550 10375);
PAINT WHITE (2550 10375);
DISPLAY INVISIBLE (2550 10375);
FORCEPROP 1 LAST PART_NUMBER CS00002JB13
J 0
(2525 10175);
DISPLAY 0.319149 (2525 10175);
DISPLAY INVISIBLE (2525 10175);
FORCEADD OFFPAGE..1
(1850 10650);
PAINT AQUA (1850 10650);
FORCEPROP 2 LAST $XR3 248 
J 0
(1424 10650);
DISPLAY 0.638298 (1424 10650);
PAINT MONO (1424 10650);
FORCEPROP 2 LAST $XR2 135 
J 0
(1424 10650);
DISPLAY 0.638298 (1424 10650);
PAINT MONO (1424 10650);
FORCEPROP 2 LAST $XR1 134 
J 0
(1424 10650);
DISPLAY 0.638298 (1424 10650);
PAINT MONO (1424 10650);
FORCEPROP 2 LAST $XR0 136 
J 0
(1424 10650);
DISPLAY 0.638298 (1424 10650);
PAINT MONO (1424 10650);
FORCEPROP 2 LAST CDS_LIB standard
J 0
(1850 10650);
DISPLAY INVISIBLE (1850 10650);
FORCEPROP 1 LAST OFFPAGE TRUE
J 0
(2175 10525);
DISPLAY 0.872340 (2175 10525);
PAINT AQUA (2175 10525);
DISPLAY INVISIBLE (2175 10525);
FORCEPROP 1 LAST COMMENT_BODY TRUE
J 0
(1975 10550);
DISPLAY 0.872340 (1975 10550);
PAINT GREEN (1975 10550);
DISPLAY INVISIBLE (1975 10550);
FORCEPROP 2 LAST PATH I124
J 0
(1900 10725);
DISPLAY 0.680851 (1900 10725);
DISPLAY INVISIBLE (1900 10725);
FORCEADD Q_RES..1
(2900 10650);
FORCEPROP 1 LAST LOCATION R561
J 0
(2700 10650);
DISPLAY 0.638298 (2700 10650);
FORCEPROP 0 LAST $SEC 1
J 0
(2700 10700);
DISPLAY 0.680851 (2700 10700);
PAINT MONO (2700 10700);
DISPLAY INVISIBLE (2700 10700);
FORCEPROP 0 LAST CDS_SEC 1
J 0
(2700 10700);
DISPLAY 0.680851 (2700 10700);
DISPLAY INVISIBLE (2700 10700);
FORCEPROP 1 LASTPIN (2800 10650) $PN 1
J 0
(2812 10662);
DISPLAY 0.787234 (2812 10662);
PAINT MONO (2812 10662);
FORCEPROP 1 LASTPIN (3000 10650) $PN 2
J 0
(2962 10662);
DISPLAY 0.787234 (2962 10662);
PAINT MONO (2962 10662);
FORCEPROP 1 LAST VALUE 0
J 2
(3050 10650);
DISPLAY 0.510638 (3050 10650);
FORCEPROP 1 LAST MATERIAL CHIP
J 0
(3125 10650);
DISPLAY 0.510638 (3125 10650);
FORCEPROP 0 LAST ROOM NIC_P12V_MAM_TIC_BOM1
J 0
(2700 10750);
DISPLAY 0.553191 (2700 10750);
PAINT RED (2700 10750);
FORCEPROP 1 LAST TOLERANCE 5%
J 0
(3075 10650);
DISPLAY 0.510638 (3075 10650);
FORCEPROP 1 LAST PACK_TYPE 0402LF
J 0
(3150 10650);
DISPLAY 0.510638 (3150 10650);
DISPLAY INVISIBLE (3150 10650);
FORCEPROP 1 LAST WATTAGE 1/16W
J 2
(3000 10575);
DISPLAY 0.319149 (3000 10575);
DISPLAY INVISIBLE (3000 10575);
FORCEPROP 2 LAST CDS_LIB pure_quanta
J 0
(2900 10650);
DISPLAY INVISIBLE (2900 10650);
FORCEPROP 1 LAST PATH I125
J 0
(2850 10800);
DISPLAY 0.978723 (2850 10800);
PAINT WHITE (2850 10800);
DISPLAY INVISIBLE (2850 10800);
FORCEPROP 1 LAST PART_NUMBER CS00002JB13
J 0
(2825 10600);
DISPLAY 0.319149 (2825 10600);
DISPLAY INVISIBLE (2825 10600);
FORCEADD Q_RES..1
(3275 11825);
FORCEPROP 1 LAST LOCATION R5487
J 0
(3225 11850);
DISPLAY 0.638298 (3225 11850);
FORCEPROP 0 LAST $SEC 1
J 0
(3225 11900);
DISPLAY 0.680851 (3225 11900);
PAINT MONO (3225 11900);
DISPLAY INVISIBLE (3225 11900);
FORCEPROP 0 LAST CDS_SEC 1
J 0
(3225 11900);
DISPLAY 0.680851 (3225 11900);
DISPLAY INVISIBLE (3225 11900);
FORCEPROP 1 LASTPIN (3175 11825) $PN 1
J 0
(3187 11837);
DISPLAY 0.787234 (3187 11837);
PAINT MONO (3187 11837);
FORCEPROP 1 LASTPIN (3375 11825) $PN 2
J 0
(3337 11837);
DISPLAY 0.787234 (3337 11837);
PAINT MONO (3337 11837);
FORCEPROP 0 LAST ROOM NIC_P3V3_BOM1
J 0
(3050 11950);
DISPLAY 0.680851 (3050 11950);
PAINT RED (3050 11950);
FORCEPROP 1 LAST VALUE 0
J 2
(3425 11825);
DISPLAY 0.510638 (3425 11825);
FORCEPROP 1 LAST TOLERANCE 5%
J 0
(3450 11825);
DISPLAY 0.510638 (3450 11825);
FORCEPROP 1 LAST PACK_TYPE 0402LF
J 0
(3050 11850);
DISPLAY 0.510638 (3050 11850);
FORCEPROP 1 LAST MATERIAL EMPTY
J 0
(3050 11825);
DISPLAY 0.510638 (3050 11825);
PAINT RED (3050 11825);
FORCEPROP 1 LAST WATTAGE 1/16W
J 2
(3375 11750);
DISPLAY 0.319149 (3375 11750);
DISPLAY INVISIBLE (3375 11750);
FORCEPROP 2 LAST CDS_LIB pure_quanta
J 0
(3275 11825);
DISPLAY INVISIBLE (3275 11825);
FORCEPROP 1 LAST PATH I126
J 0
(3225 11975);
DISPLAY 0.978723 (3225 11975);
PAINT WHITE (3225 11975);
DISPLAY INVISIBLE (3225 11975);
FORCEPROP 1 LAST PART_NUMBER CS00002JB13
J 0
(3200 11775);
DISPLAY 0.319149 (3200 11775);
DISPLAY INVISIBLE (3200 11775);
FORCEADD Q_RES..2
R 2
(3650 11500);
FORCEPROP 1 LAST LOCATION R4069
J 2
(3605 11625);
DISPLAY 0.808511 (3605 11625);
FORCEPROP 0 LAST $SEC 1
J 0
(3625 11675);
DISPLAY 0.680851 (3625 11675);
PAINT MONO (3625 11675);
DISPLAY INVISIBLE (3625 11675);
FORCEPROP 0 LAST CDS_SEC 1
J 0
(3625 11675);
DISPLAY 0.680851 (3625 11675);
DISPLAY INVISIBLE (3625 11675);
FORCEPROP 1 LASTPIN (3650 11600) $PN 1
J 2
(3645 11562);
DISPLAY 0.787234 (3645 11562);
PAINT MONO (3645 11562);
FORCEPROP 1 LASTPIN (3650 11400) $PN 2
J 2
(3645 11410);
DISPLAY 0.787234 (3645 11410);
PAINT MONO (3645 11410);
FORCEPROP 1 LAST VALUE 4.7K
J 2
(3605 11575);
DISPLAY 0.638298 (3605 11575);
FORCEPROP 1 LAST MATERIAL EMPTY
J 2
(3610 11425);
DISPLAY 0.638298 (3610 11425);
PAINT RED (3610 11425);
FORCEPROP 0 LAST ROOM NIC_P3V3_BOM1
J 0
(3200 11675);
DISPLAY 0.680851 (3200 11675);
PAINT RED (3200 11675);
FORCEPROP 1 LAST PACK_TYPE 0402LF
J 2
(3610 11325);
DISPLAY 0.638298 (3610 11325);
FORCEPROP 1 LAST WATTAGE 1/16W
J 2
(3610 11475);
DISPLAY 0.638298 (3610 11475);
FORCEPROP 1 LAST TOLERANCE 5%
J 2
(3605 11525);
DISPLAY 0.638298 (3605 11525);
FORCEPROP 2 LAST CDS_LIB pure_quanta
J 2
(3650 11500);
DISPLAY INVISIBLE (3650 11500);
FORCEPROP 1 LAST PATH I127
J 2
(3600 11675);
DISPLAY 0.978723 (3600 11675);
PAINT WHITE (3600 11675);
DISPLAY INVISIBLE (3600 11675);
FORCEPROP 1 LAST PART_NUMBER CS24702JB10
J 2
(3610 11375);
DISPLAY 0.638298 (3610 11375);
DISPLAY INVISIBLE (3610 11375);
FORCEADD OFFPAGE..1
(2100 12225);
PAINT AQUA (2100 12225);
FORCEPROP 2 LAST $XR3 248 
J 0
(1728 12189);
DISPLAY 0.638298 (1728 12189);
PAINT MONO (1728 12189);
FORCEPROP 2 LAST $XR2 136 
J 0
(1848 12189);
DISPLAY 0.638298 (1848 12189);
PAINT MONO (1848 12189);
FORCEPROP 2 LAST $XR1 135 
J 0
(1728 12225);
DISPLAY 0.638298 (1728 12225);
PAINT MONO (1728 12225);
FORCEPROP 2 LAST $XR0 134 
J 0
(1848 12225);
DISPLAY 0.638298 (1848 12225);
PAINT MONO (1848 12225);
FORCEPROP 2 LAST CDS_LIB standard
J 0
(2100 12225);
DISPLAY INVISIBLE (2100 12225);
FORCEPROP 1 LAST OFFPAGE TRUE
J 0
(2425 12100);
DISPLAY 0.872340 (2425 12100);
PAINT AQUA (2425 12100);
DISPLAY INVISIBLE (2425 12100);
FORCEPROP 1 LAST COMMENT_BODY TRUE
J 0
(2225 12125);
DISPLAY 0.872340 (2225 12125);
PAINT GREEN (2225 12125);
DISPLAY INVISIBLE (2225 12125);
FORCEPROP 2 LAST PATH I129
J 0
(2150 12300);
DISPLAY 0.680851 (2150 12300);
DISPLAY INVISIBLE (2150 12300);
FORCEADD OFFPAGE..1
(3850 9400);
FORCEPROP 2 LAST $XR1 143 
J 0
(3448 9400);
DISPLAY 0.638298 (3448 9400);
PAINT MONO (3448 9400);
FORCEPROP 2 LAST $XR0 131 
J 0
(3568 9400);
DISPLAY 0.638298 (3568 9400);
PAINT MONO (3568 9400);
FORCEPROP 2 LAST CDS_LIB standard
J 0
(3850 9400);
PAINT MONO (3850 9400);
DISPLAY INVISIBLE (3850 9400);
FORCEPROP 1 LAST OFFPAGE TRUE
J 0
(4175 9275);
DISPLAY 0.872340 (4175 9275);
PAINT GREEN (4175 9275);
DISPLAY INVISIBLE (4175 9275);
FORCEPROP 1 LAST COMMENT_BODY TRUE
J 0
(3975 9300);
DISPLAY 0.872340 (3975 9300);
PAINT GREEN (3975 9300);
DISPLAY INVISIBLE (3975 9300);
FORCEPROP 2 LAST PATH I13
J 0
(3600 9450);
DISPLAY 0.680851 (3600 9450);
DISPLAY INVISIBLE (3600 9450);
FORCEADD Q_RES..2
R 2
(3025 9900);
FORCEPROP 1 LAST LOCATION R6045
J 2
(2980 10025);
DISPLAY 0.808511 (2980 10025);
FORCEPROP 0 LAST $SEC 1
J 0
(3000 10075);
DISPLAY 0.680851 (3000 10075);
PAINT MONO (3000 10075);
DISPLAY INVISIBLE (3000 10075);
FORCEPROP 0 LAST CDS_SEC 1
J 0
(3000 10075);
DISPLAY 0.680851 (3000 10075);
DISPLAY INVISIBLE (3000 10075);
FORCEPROP 1 LASTPIN (3025 10000) $PN 1
J 2
(3020 9962);
DISPLAY 0.787234 (3020 9962);
PAINT MONO (3020 9962);
FORCEPROP 1 LASTPIN (3025 9800) $PN 2
J 2
(3020 9810);
DISPLAY 0.787234 (3020 9810);
PAINT MONO (3020 9810);
FORCEPROP 1 LAST WATTAGE 1/16W
J 2
(2985 9875);
DISPLAY 0.638298 (2985 9875);
FORCEPROP 1 LAST PACK_TYPE 0402LF
J 2
(2985 9725);
DISPLAY 0.638298 (2985 9725);
FORCEPROP 1 LAST TOLERANCE 5%
J 2
(2980 9925);
DISPLAY 0.638298 (2980 9925);
FORCEPROP 1 LAST VALUE 4.7K
J 2
(2980 9975);
DISPLAY 0.638298 (2980 9975);
FORCEPROP 1 LAST MATERIAL EMPTY
J 2
(2985 9825);
DISPLAY 0.638298 (2985 9825);
PAINT RED (2985 9825);
FORCEPROP 0 LAST ROOM NIC_P12V_MAM_TIC_BOM1
J 0
(2325 9650);
DISPLAY 0.680851 (2325 9650);
PAINT RED (2325 9650);
FORCEPROP 2 LAST CDS_LIB pure_quanta
J 0
(3025 9900);
DISPLAY INVISIBLE (3025 9900);
FORCEPROP 1 LAST PATH I130
J 2
(2975 10075);
DISPLAY 0.978723 (2975 10075);
PAINT WHITE (2975 10075);
DISPLAY INVISIBLE (2975 10075);
FORCEPROP 1 LAST PART_NUMBER CS24702JB10
J 2
(2985 9775);
DISPLAY 0.638298 (2985 9775);
DISPLAY INVISIBLE (2985 9775);
FORCEADD Q_RES..2
(10225 13050);
FORCEPROP 1 LAST LOCATION R3783
J 0
(10270 13175);
DISPLAY 0.638298 (10270 13175);
FORCEPROP 0 LAST $SEC 1
J 0
(10275 13225);
DISPLAY 0.680851 (10275 13225);
PAINT MONO (10275 13225);
DISPLAY INVISIBLE (10275 13225);
FORCEPROP 0 LAST CDS_SEC 1
J 0
(10275 13225);
DISPLAY 0.680851 (10275 13225);
DISPLAY INVISIBLE (10275 13225);
FORCEPROP 1 LASTPIN (10225 13150) $PN 1
J 0
(10230 13112);
DISPLAY 0.787234 (10230 13112);
PAINT MONO (10230 13112);
FORCEPROP 1 LASTPIN (10225 12950) $PN 2
J 0
(10230 12960);
DISPLAY 0.787234 (10230 12960);
PAINT MONO (10230 12960);
FORCEPROP 1 LAST PACK_TYPE 0402LF
J 0
(10265 12875);
DISPLAY 0.510638 (10265 12875);
FORCEPROP 0 LAST ROOM NIC_P3V3_BOM1
J 0
(10275 13225);
DISPLAY 0.553191 (10275 13225);
PAINT RED (10275 13225);
FORCEPROP 1 LAST MATERIAL EMPTY
J 0
(10265 12975);
DISPLAY 0.510638 (10265 12975);
PAINT RED (10265 12975);
FORCEPROP 1 LAST WATTAGE 1/16W
J 0
(10265 13025);
DISPLAY 0.510638 (10265 13025);
FORCEPROP 1 LAST TOLERANCE 1%
J 0
(10270 13075);
DISPLAY 0.510638 (10270 13075);
FORCEPROP 1 LAST VALUE 100K
J 0
(10270 13125);
DISPLAY 0.510638 (10270 13125);
FORCEPROP 2 LAST CDS_LIB pure_quanta
J 0
(10225 13050);
DISPLAY INVISIBLE (10225 13050);
FORCEPROP 1 LAST PATH I131
J 0
(10275 13225);
DISPLAY 0.978723 (10275 13225);
PAINT WHITE (10275 13225);
DISPLAY INVISIBLE (10275 13225);
FORCEPROP 1 LAST PART_NUMBER CS41002FB09
J 0
(10265 12925);
DISPLAY 0.510638 (10265 12925);
DISPLAY INVISIBLE (10265 12925);
FORCEADD Q_RES..1
(9325 12775);
FORCEPROP 1 LAST LOCATION R3794
J 0
(8975 12775);
DISPLAY 0.638298 (8975 12775);
FORCEPROP 0 LAST $SEC 1
J 0
(8975 12825);
DISPLAY 0.680851 (8975 12825);
PAINT MONO (8975 12825);
DISPLAY INVISIBLE (8975 12825);
FORCEPROP 0 LAST CDS_SEC 1
J 0
(8975 12825);
DISPLAY 0.680851 (8975 12825);
DISPLAY INVISIBLE (8975 12825);
FORCEPROP 1 LASTPIN (9225 12775) $PN 1
J 0
(9237 12787);
DISPLAY 0.787234 (9237 12787);
PAINT MONO (9237 12787);
FORCEPROP 1 LASTPIN (9425 12775) $PN 2
J 0
(9387 12787);
DISPLAY 0.787234 (9387 12787);
PAINT MONO (9387 12787);
FORCEPROP 1 LAST MATERIAL EMPTY
J 0
(9100 12775);
DISPLAY 0.510638 (9100 12775);
PAINT RED (9100 12775);
FORCEPROP 1 LAST WATTAGE 1/16W
J 2
(9100 12725);
DISPLAY 0.510638 (9100 12725);
FORCEPROP 0 LAST ROOM NIC_P3V3_BOM1
J 0
(9075 12700);
DISPLAY 0.446809 (9075 12700);
PAINT RED (9075 12700);
FORCEPROP 1 LAST VALUE 0
J 2
(9475 12775);
DISPLAY 0.510638 (9475 12775);
FORCEPROP 1 LAST TOLERANCE 5%
J 0
(9500 12775);
DISPLAY 0.510638 (9500 12775);
FORCEPROP 1 LAST PACK_TYPE 0402LF
J 0
(9475 12725);
DISPLAY 0.510638 (9475 12725);
FORCEPROP 2 LAST CDS_LIB pure_quanta
J 0
(9325 12775);
DISPLAY INVISIBLE (9325 12775);
FORCEPROP 1 LAST PATH I132
J 0
(9275 12925);
DISPLAY 0.978723 (9275 12925);
PAINT WHITE (9275 12925);
DISPLAY INVISIBLE (9275 12925);
FORCEPROP 1 LAST PART_NUMBER CS00002JB13
J 0
(9150 12725);
DISPLAY 0.510638 (9150 12725);
DISPLAY INVISIBLE (9150 12725);
FORCEADD Q_RES..1
(3325 12225);
FORCEPROP 1 LAST LOCATION R1136
J 0
(3275 12250);
DISPLAY 0.638298 (3275 12250);
FORCEPROP 0 LAST $SEC 1
J 0
(3100 12400);
DISPLAY 0.680851 (3100 12400);
PAINT MONO (3100 12400);
DISPLAY INVISIBLE (3100 12400);
FORCEPROP 0 LAST CDS_SEC 1
J 0
(3100 12400);
DISPLAY 0.680851 (3100 12400);
DISPLAY INVISIBLE (3100 12400);
FORCEPROP 1 LASTPIN (3225 12225) $PN 1
J 0
(3237 12237);
DISPLAY 0.787234 (3237 12237);
PAINT MONO (3237 12237);
FORCEPROP 1 LASTPIN (3425 12225) $PN 2
J 0
(3387 12237);
DISPLAY 0.787234 (3387 12237);
PAINT MONO (3387 12237);
FORCEPROP 1 LAST TOLERANCE 5%
J 0
(3500 12225);
DISPLAY 0.510638 (3500 12225);
FORCEPROP 1 LAST VALUE 0
J 2
(3475 12225);
DISPLAY 0.510638 (3475 12225);
FORCEPROP 1 LAST PACK_TYPE 0402LF
J 0
(3100 12250);
DISPLAY 0.510638 (3100 12250);
FORCEPROP 0 LAST ROOM NIC_P3V3_BOM1
J 0
(3100 12350);
DISPLAY 0.680851 (3100 12350);
PAINT RED (3100 12350);
FORCEPROP 1 LAST MATERIAL EMPTY
J 0
(3100 12225);
DISPLAY 0.510638 (3100 12225);
PAINT RED (3100 12225);
FORCEPROP 2 LAST CDS_LIB pure_quanta
J 0
(3325 12225);
DISPLAY INVISIBLE (3325 12225);
FORCEPROP 1 LAST WATTAGE 1/16W
J 2
(3425 12150);
DISPLAY 0.319149 (3425 12150);
DISPLAY INVISIBLE (3425 12150);
FORCEPROP 1 LAST PATH I133
J 0
(3275 12375);
DISPLAY 0.978723 (3275 12375);
PAINT WHITE (3275 12375);
DISPLAY INVISIBLE (3275 12375);
FORCEPROP 1 LAST PART_NUMBER CS00002JB13
J 0
(3250 12175);
DISPLAY 0.319149 (3250 12175);
DISPLAY INVISIBLE (3250 12175);
FORCEADD OFFPAGE..1
(2075 12650);
PAINT AQUA (2075 12650);
FORCEPROP 2 LAST $XR3 248 
J 0
(1703 12614);
DISPLAY 0.638298 (1703 12614);
PAINT MONO (1703 12614);
FORCEPROP 2 LAST $XR2 135 
J 0
(1823 12614);
DISPLAY 0.638298 (1823 12614);
PAINT MONO (1823 12614);
FORCEPROP 2 LAST $XR1 134 
J 0
(1703 12650);
DISPLAY 0.638298 (1703 12650);
PAINT MONO (1703 12650);
FORCEPROP 2 LAST $XR0 136 
J 0
(1823 12650);
DISPLAY 0.638298 (1823 12650);
PAINT MONO (1823 12650);
FORCEPROP 2 LAST CDS_LIB standard
J 0
(2075 12650);
DISPLAY INVISIBLE (2075 12650);
FORCEPROP 1 LAST OFFPAGE TRUE
J 0
(2400 12525);
DISPLAY 0.872340 (2400 12525);
PAINT AQUA (2400 12525);
DISPLAY INVISIBLE (2400 12525);
FORCEPROP 1 LAST COMMENT_BODY TRUE
J 0
(2200 12550);
DISPLAY 0.872340 (2200 12550);
PAINT GREEN (2200 12550);
DISPLAY INVISIBLE (2200 12550);
FORCEPROP 2 LAST PATH I134
J 0
(2125 12725);
DISPLAY 0.680851 (2125 12725);
DISPLAY INVISIBLE (2125 12725);
FORCEADD Q_RES..1
(3275 12650);
FORCEPROP 1 LAST LOCATION R1486
J 0
(3050 12700);
DISPLAY 0.978723 (3050 12700);
PAINT SKYBLUE (3050 12700);
FORCEPROP 0 LAST $SEC 1
J 0
(3075 12825);
DISPLAY 0.680851 (3075 12825);
PAINT MONO (3075 12825);
DISPLAY INVISIBLE (3075 12825);
FORCEPROP 0 LAST CDS_SEC 1
J 0
(3075 12825);
DISPLAY 0.680851 (3075 12825);
DISPLAY INVISIBLE (3075 12825);
FORCEPROP 1 LASTPIN (3175 12650) $PN 1
J 0
(3187 12662);
DISPLAY 0.787234 (3187 12662);
PAINT MONO (3187 12662);
FORCEPROP 1 LASTPIN (3375 12650) $PN 2
J 0
(3337 12662);
DISPLAY 0.787234 (3337 12662);
PAINT MONO (3337 12662);
FORCEPROP 0 LAST ROOM NIC_P3V3_BOM1
J 0
(3075 12775);
DISPLAY 0.680851 (3075 12775);
PAINT RED (3075 12775);
FORCEPROP 1 LAST PACK_TYPE 0402LF
J 0
(3025 12650);
DISPLAY 0.510638 (3025 12650);
FORCEPROP 1 LAST MATERIAL CHIP
J 0
(3075 12625);
DISPLAY 0.510638 (3075 12625);
FORCEPROP 1 LAST WATTAGE 1/16W
J 2
(3450 12575);
DISPLAY 0.510638 (3450 12575);
FORCEPROP 1 LAST TOLERANCE 5%
J 0
(3425 12650);
DISPLAY 0.510638 (3425 12650);
FORCEPROP 1 LAST VALUE 0
J 2
(3400 12650);
DISPLAY 0.510638 (3400 12650);
FORCEPROP 2 LAST CDS_LIB pure_quanta
J 0
(3275 12650);
DISPLAY INVISIBLE (3275 12650);
FORCEPROP 1 LAST PATH I135
J 0
(3225 12800);
DISPLAY 0.978723 (3225 12800);
PAINT WHITE (3225 12800);
DISPLAY INVISIBLE (3225 12800);
FORCEPROP 1 LAST PART_NUMBER CS00002JB13
J 0
(3200 12600);
DISPLAY 0.510638 (3200 12600);
DISPLAY INVISIBLE (3200 12600);
FORCEADD OFFPAGE..1
(3850 9500);
FORCEPROP 2 LAST $XR1 143 
J 0
(3448 9500);
DISPLAY 0.638298 (3448 9500);
PAINT MONO (3448 9500);
FORCEPROP 2 LAST $XR0 131 
J 0
(3568 9500);
DISPLAY 0.638298 (3568 9500);
PAINT MONO (3568 9500);
FORCEPROP 2 LAST CDS_LIB standard
J 0
(3850 9500);
PAINT MONO (3850 9500);
DISPLAY INVISIBLE (3850 9500);
FORCEPROP 1 LAST OFFPAGE TRUE
J 0
(4175 9375);
DISPLAY 0.872340 (4175 9375);
PAINT GREEN (4175 9375);
DISPLAY INVISIBLE (4175 9375);
FORCEPROP 1 LAST COMMENT_BODY TRUE
J 0
(3975 9400);
DISPLAY 0.872340 (3975 9400);
PAINT GREEN (3975 9400);
DISPLAY INVISIBLE (3975 9400);
FORCEPROP 2 LAST PATH I14
J 0
(3600 9550);
DISPLAY 0.680851 (3600 9550);
DISPLAY INVISIBLE (3600 9550);
FORCEADD Q_RES..2
(3950 9750);
FORCEPROP 1 LAST LOCATION R1905
J 0
(3995 9875);
DISPLAY 0.978723 (3995 9875);
FORCEPROP 0 LAST $SEC 1
J 0
(4000 9925);
DISPLAY 0.680851 (4000 9925);
PAINT MONO (4000 9925);
DISPLAY INVISIBLE (4000 9925);
FORCEPROP 0 LAST CDS_SEC 1
J 0
(4000 9925);
DISPLAY 1.021277 (4000 9925);
DISPLAY INVISIBLE (4000 9925);
FORCEPROP 1 LASTPIN (3950 9850) $PN 1
J 0
(3955 9812);
DISPLAY 0.787234 (3955 9812);
PAINT MONO (3955 9812);
FORCEPROP 1 LASTPIN (3950 9650) $PN 2
J 0
(3955 9660);
DISPLAY 0.787234 (3955 9660);
PAINT MONO (3955 9660);
FORCEPROP 1 LAST WATTAGE 1/16W
J 0
(3990 9725);
DISPLAY 0.638298 (3990 9725);
FORCEPROP 1 LAST TOLERANCE 1%
J 0
(3995 9775);
DISPLAY 0.638298 (3995 9775);
FORCEPROP 1 LAST PACK_TYPE 0402LF
J 0
(3990 9625);
DISPLAY 0.638298 (3990 9625);
FORCEPROP 1 LAST MATERIAL CHIP
J 0
(3990 9675);
DISPLAY 0.638298 (3990 9675);
FORCEPROP 1 LAST VALUE 1K
J 0
(3995 9825);
DISPLAY 0.638298 (3995 9825);
FORCEPROP 2 LAST CDS_LIB pure_quanta
J 0
(3950 9750);
DISPLAY INVISIBLE (3950 9750);
FORCEPROP 1 LAST PATH I15
J 0
(4000 9925);
DISPLAY 0.978723 (4000 9925);
PAINT WHITE (4000 9925);
DISPLAY INVISIBLE (4000 9925);
FORCEPROP 1 LAST PART_NUMBER CS21002FB06
J 0
(3990 9625);
DISPLAY 0.638298 (3990 9625);
DISPLAY INVISIBLE (3990 9625);
FORCEADD UNIVERSAL_POWER..1
(4150 10050);
FORCEPROP 3 LASTPIN (4150 10000) SIG_NAME P3V3_AUX\g
J 0
(4160 10010);
DISPLAY 0.659574 (4160 10010);
PAINT MONO (4160 10010);
DISPLAY INVISIBLE (4160 10010);
FORCEPROP 1 LAST HDL_POWER P3V3_AUX
J 1
(4150 10100);
DISPLAY 0.872340 (4150 10100);
PAINT GREEN (4150 10100);
FORCEPROP 2 LAST CDS_LIB pure_quanta_power
J 0
(4150 10050);
DISPLAY INVISIBLE (4150 10050);
FORCEPROP 1 LAST PATH I16
J 0
(4200 10075);
DISPLAY 0.872340 (4200 10075);
PAINT AQUA (4200 10075);
DISPLAY INVISIBLE (4200 10075);
FORCEADD Q_RES..2
(3475 10800);
FORCEPROP 1 LAST LOCATION R4068
J 0
(3510 10967);
DISPLAY 0.638298 (3510 10967);
FORCEPROP 0 LAST $SEC 1
J 0
(3525 11000);
DISPLAY 0.680851 (3525 11000);
PAINT MONO (3525 11000);
DISPLAY INVISIBLE (3525 11000);
FORCEPROP 0 LAST CDS_SEC 1
J 0
(3525 11000);
DISPLAY 1.021277 (3525 11000);
DISPLAY INVISIBLE (3525 11000);
FORCEPROP 1 LASTPIN (3475 10900) $PN 1
J 0
(3480 10862);
DISPLAY 0.787234 (3480 10862);
PAINT MONO (3480 10862);
FORCEPROP 1 LASTPIN (3475 10700) $PN 2
J 0
(3480 10710);
DISPLAY 0.787234 (3480 10710);
PAINT MONO (3480 10710);
FORCEPROP 1 LAST PACK_TYPE 0402LF
J 0
(3505 10667);
DISPLAY 0.638298 (3505 10667);
FORCEPROP 1 LAST VALUE 10K
J 0
(3510 10917);
DISPLAY 0.638298 (3510 10917);
FORCEPROP 1 LAST WATTAGE 1/16W
J 0
(3505 10817);
DISPLAY 0.638298 (3505 10817);
FORCEPROP 1 LAST TOLERANCE 1%
J 0
(3510 10867);
DISPLAY 0.638298 (3510 10867);
FORCEPROP 1 LAST MATERIAL CHIP
J 0
(3505 10767);
DISPLAY 0.638298 (3505 10767);
FORCEPROP 0 LAST ROOM NIC_P12V_MAM_TIC_BOM1
J 0
(3525 11050);
DISPLAY 0.680851 (3525 11050);
PAINT RED (3525 11050);
FORCEPROP 2 LAST CDS_LIB pure_quanta
J 0
(3475 10800);
DISPLAY INVISIBLE (3475 10800);
FORCEPROP 1 LAST PATH I17
J 0
(3525 10975);
DISPLAY 0.978723 (3525 10975);
PAINT WHITE (3525 10975);
DISPLAY INVISIBLE (3525 10975);
FORCEPROP 1 LAST PART_NUMBER CS31002FB08
J 0
(3505 10717);
DISPLAY 0.638298 (3505 10717);
DISPLAY INVISIBLE (3505 10717);
FORCEADD UNIVERSAL_POWER..1
(3475 11125);
FORCEPROP 3 LASTPIN (3475 11075) SIG_NAME P12V_AUX\g
J 0
(3485 11085);
DISPLAY 0.659574 (3485 11085);
PAINT MONO (3485 11085);
DISPLAY INVISIBLE (3485 11085);
FORCEPROP 1 LAST HDL_POWER P12V_AUX
J 1
(3475 11175);
DISPLAY 0.872340 (3475 11175);
PAINT GREEN (3475 11175);
FORCEPROP 2 LAST CDS_LIB pure_quanta_power
J 0
(3475 11125);
DISPLAY INVISIBLE (3475 11125);
FORCEPROP 1 LAST PATH I18
J 0
(3525 11150);
DISPLAY 0.872340 (3525 11150);
PAINT AQUA (3525 11150);
DISPLAY INVISIBLE (3525 11150);
FORCEADD MOSFET_NCH_DUAL..2
(4425 10575);
FORCEPROP 1 LAST LOCATION Q123
J 0
(4576 10551);
DISPLAY 0.723404 (4576 10551);
PAINT GREEN (4576 10551);
FORCEPROP 0 LAST $SEC 2
J 0
(4600 10700);
DISPLAY 0.680851 (4600 10700);
PAINT MONO (4600 10700);
DISPLAY INVISIBLE (4600 10700);
FORCEPROP 0 LAST CDS_SEC 2
J 0
(4600 10700);
DISPLAY 1.021277 (4600 10700);
DISPLAY INVISIBLE (4600 10700);
FORCEPROP 0 LASTPIN (4475 10775) $PN 3
R 1
J 0
(4465 10785);
DISPLAY 0.680851 (4465 10785);
PAINT MONO (4465 10785);
FORCEPROP 0 LASTPIN (4225 10525) $PN 5
J 2
(4215 10535);
DISPLAY 0.680851 (4215 10535);
PAINT MONO (4215 10535);
FORCEPROP 0 LASTPIN (4475 10375) $PN 4
R 1
J 2
(4465 10365);
DISPLAY 0.680851 (4465 10365);
PAINT MONO (4465 10365);
FORCEPROP 1 LAST MATERIAL IC
J 0
(4576 10426);
DISPLAY 0.723404 (4576 10426);
PAINT GREEN (4576 10426);
FORCEPROP 0 LAST ROOM NIC_P12V_MAM_TIC_BOM1
J 0
(4600 10725);
DISPLAY 0.680851 (4600 10725);
PAINT RED (4600 10725);
FORCEPROP 2 LAST PART_TYPE SMLF
J 0
(4600 10650);
DISPLAY 1.021277 (4600 10650);
FORCEPROP 2 LAST VALUE PJT138K
J 0
(4600 10600);
DISPLAY 1.021277 (4600 10600);
FORCEPROP 2 LAST CDS_LIB pure_quanta
J 0
(4425 10575);
DISPLAY INVISIBLE (4425 10575);
FORCEPROP 1 LAST CDS_LMAN_SYM_OUTLINE -150,150,150,-150
J 0
(4425 10575);
DISPLAY 0.468085 (4425 10575);
PAINT GREEN (4425 10575);
DISPLAY INVISIBLE (4425 10575);
FORCEPROP 1 LAST NEEDS_NO_SIZE TRUE
J 0
(4575 10466);
DISPLAY 0.468085 (4575 10466);
PAINT GREEN (4575 10466);
DISPLAY INVISIBLE (4575 10466);
FORCEPROP 1 LAST PATH I19
J 0
(4575 10425);
DISPLAY 0.723404 (4575 10425);
PAINT GREEN (4575 10425);
DISPLAY INVISIBLE (4575 10425);
FORCEPROP 1 LAST PART_NUMBER BAM138K0003
J 0
(4576 10481);
DISPLAY 0.723404 (4576 10481);
PAINT GREEN (4576 10481);
DISPLAY INVISIBLE (4576 10481);
FORCEADD OFFPAGE..1
(1875 10225);
PAINT AQUA (1875 10225);
FORCEPROP 2 LAST $XR3 136 
J 0
(1654 10117);
DISPLAY 0.638298 (1654 10117);
PAINT MONO (1654 10117);
FORCEPROP 2 LAST $XR2 135 
J 0
(1654 10153);
DISPLAY 0.638298 (1654 10153);
PAINT MONO (1654 10153);
FORCEPROP 2 LAST $XR1 83 
J 0
(1654 10189);
DISPLAY 0.638298 (1654 10189);
PAINT MONO (1654 10189);
FORCEPROP 2 LAST $XR0 80 
J 0
(1654 10225);
DISPLAY 0.638298 (1654 10225);
PAINT MONO (1654 10225);
FORCEPROP 2 LAST CDS_LIB standard
J 0
(1875 10225);
DISPLAY INVISIBLE (1875 10225);
FORCEPROP 1 LAST OFFPAGE TRUE
J 0
(2200 10100);
DISPLAY 0.872340 (2200 10100);
PAINT AQUA (2200 10100);
DISPLAY INVISIBLE (2200 10100);
FORCEPROP 1 LAST COMMENT_BODY TRUE
J 0
(2000 10125);
DISPLAY 0.872340 (2000 10125);
PAINT GREEN (2000 10125);
DISPLAY INVISIBLE (2000 10125);
FORCEPROP 2 LAST PATH I2
J 0
(1925 10300);
DISPLAY 0.680851 (1925 10300);
DISPLAY INVISIBLE (1925 10300);
FORCEADD GND..1
(3650 11250);
FORCEPROP 3 LASTPIN (3650 11300) SIG_NAME GND\g
J 0
(3660 11310);
DISPLAY 0.659574 (3660 11310);
PAINT MONO (3660 11310);
DISPLAY INVISIBLE (3660 11310);
FORCEPROP 2 LAST CDS_LIB pure_quanta_power
J 0
(3650 11250);
DISPLAY INVISIBLE (3650 11250);
FORCEPROP 1 LAST SIZE 1B
J 0
(3725 11200);
DISPLAY 0.872340 (3725 11200);
PAINT GREEN (3725 11200);
DISPLAY INVISIBLE (3725 11200);
FORCEPROP 1 LAST HDL_POWER GND
J 0
(3650 11400);
DISPLAY 0.872340 (3650 11400);
PAINT GREEN (3650 11400);
DISPLAY INVISIBLE (3650 11400);
FORCEPROP 1 LAST PATH I20
J 0
(3725 11250);
DISPLAY 0.872340 (3725 11250);
PAINT AQUA (3725 11250);
DISPLAY INVISIBLE (3725 11250);
FORCEADD MOSFET_NCH_DUAL..1
(4175 11875);
FORCEPROP 1 LAST LOCATION Q124
J 0
(4326 11849);
DISPLAY 0.723404 (4326 11849);
PAINT GREEN (4326 11849);
FORCEPROP 0 LAST $SEC 1
J 0
(4350 12000);
DISPLAY 0.680851 (4350 12000);
PAINT MONO (4350 12000);
DISPLAY INVISIBLE (4350 12000);
FORCEPROP 0 LAST CDS_SEC 1
J 0
(4350 12000);
DISPLAY 1.021277 (4350 12000);
DISPLAY INVISIBLE (4350 12000);
FORCEPROP 0 LASTPIN (4225 12075) $PN 6
R 1
J 0
(4215 12085);
DISPLAY 0.680851 (4215 12085);
PAINT MONO (4215 12085);
FORCEPROP 0 LASTPIN (3975 11825) $PN 2
J 2
(3965 11835);
DISPLAY 0.680851 (3965 11835);
PAINT MONO (3965 11835);
FORCEPROP 0 LASTPIN (4225 11675) $PN 1
R 1
J 2
(4215 11665);
DISPLAY 0.680851 (4215 11665);
PAINT MONO (4215 11665);
FORCEPROP 2 LAST PART_TYPE SMLF
J 0
(4350 11950);
DISPLAY 1.021277 (4350 11950);
FORCEPROP 2 LAST VALUE PJT138K
J 0
(4350 11900);
DISPLAY 1.021277 (4350 11900);
FORCEPROP 0 LAST ROOM NIC_P3V3_BOM1
J 0
(4350 12050);
DISPLAY 0.680851 (4350 12050);
PAINT RED (4350 12050);
FORCEPROP 1 LAST MATERIAL IC
J 0
(4326 11724);
DISPLAY 0.723404 (4326 11724);
PAINT GREEN (4326 11724);
FORCEPROP 2 LAST CDS_LIB pure_quanta
J 0
(4175 11875);
DISPLAY INVISIBLE (4175 11875);
FORCEPROP 1 LAST CDS_LMAN_SYM_OUTLINE -150,150,150,-150
J 0
(4175 11875);
DISPLAY 0.468085 (4175 11875);
PAINT GREEN (4175 11875);
DISPLAY INVISIBLE (4175 11875);
FORCEPROP 1 LAST NEEDS_NO_SIZE TRUE
J 0
(4175 11874);
DISPLAY 0.468085 (4175 11874);
PAINT GREEN (4175 11874);
DISPLAY INVISIBLE (4175 11874);
FORCEPROP 1 LAST PATH I23
J 0
(4175 11875);
DISPLAY 0.723404 (4175 11875);
PAINT GREEN (4175 11875);
DISPLAY INVISIBLE (4175 11875);
FORCEPROP 1 LAST PART_NUMBER BAM138K0003
J 0
(4326 11789);
DISPLAY 0.723404 (4326 11789);
PAINT GREEN (4326 11789);
DISPLAY INVISIBLE (4326 11789);
FORCEADD Q_RES..2
(4125 8850);
FORCEPROP 1 LAST LOCATION R1908
J 0
(4170 8975);
DISPLAY 0.978723 (4170 8975);
FORCEPROP 0 LAST $SEC 1
J 0
(4175 9025);
DISPLAY 0.680851 (4175 9025);
PAINT MONO (4175 9025);
DISPLAY INVISIBLE (4175 9025);
FORCEPROP 0 LAST CDS_SEC 1
J 0
(4175 9025);
DISPLAY 1.021277 (4175 9025);
DISPLAY INVISIBLE (4175 9025);
FORCEPROP 1 LASTPIN (4125 8950) $PN 1
J 0
(4130 8912);
DISPLAY 0.787234 (4130 8912);
PAINT MONO (4130 8912);
FORCEPROP 1 LASTPIN (4125 8750) $PN 2
J 0
(4130 8760);
DISPLAY 0.787234 (4130 8760);
PAINT MONO (4130 8760);
FORCEPROP 1 LAST TOLERANCE 1%
J 0
(4170 8875);
DISPLAY 0.638298 (4170 8875);
FORCEPROP 1 LAST PACK_TYPE 0402LF
J 0
(4165 8725);
DISPLAY 0.638298 (4165 8725);
FORCEPROP 1 LAST MATERIAL CHIP
J 0
(4165 8775);
DISPLAY 0.638298 (4165 8775);
FORCEPROP 1 LAST WATTAGE 1/16W
J 0
(4165 8825);
DISPLAY 0.638298 (4165 8825);
FORCEPROP 1 LAST VALUE 1K
J 0
(4170 8925);
DISPLAY 0.638298 (4170 8925);
FORCEPROP 2 LAST CDS_LIB pure_quanta
J 0
(4125 8850);
DISPLAY INVISIBLE (4125 8850);
FORCEPROP 1 LAST PATH I24
J 0
(4175 9025);
DISPLAY 0.978723 (4175 9025);
PAINT WHITE (4175 9025);
DISPLAY INVISIBLE (4175 9025);
FORCEPROP 1 LAST PART_NUMBER CS21002FB06
J 0
(4165 8725);
DISPLAY 0.638298 (4165 8725);
DISPLAY INVISIBLE (4165 8725);
FORCEADD UNIVERSAL_GND..1
(4875 8250);
FORCEPROP 3 LASTPIN (4875 8300) SIG_NAME GND\g
J 0
(4885 8310);
DISPLAY 0.659574 (4885 8310);
PAINT MONO (4885 8310);
DISPLAY INVISIBLE (4885 8310);
FORCEPROP 2 LAST CDS_LIB pure_quanta_power
J 0
(4875 8250);
PAINT MONO (4875 8250);
DISPLAY INVISIBLE (4875 8250);
FORCEPROP 1 LAST HDL_POWER GND
J 1
(4900 8175);
DISPLAY 0.872340 (4900 8175);
PAINT GREEN (4900 8175);
DISPLAY INVISIBLE (4900 8175);
FORCEPROP 1 LAST PATH I25
J 0
(4950 8250);
DISPLAY 0.872340 (4950 8250);
PAINT AQUA (4950 8250);
DISPLAY INVISIBLE (4950 8250);
FORCEADD 74LVC2G07DW7..1
(5275 8550);
FORCEPROP 1 LAST LOCATION U8
J 0
(5106 8931);
DISPLAY 0.723404 (5106 8931);
PAINT GREEN (5106 8931);
FORCEPROP 0 LAST $SEC 1
J 0
(5125 9075);
DISPLAY 0.680851 (5125 9075);
PAINT MONO (5125 9075);
DISPLAY INVISIBLE (5125 9075);
FORCEPROP 0 LAST CDS_SEC 1
J 0
(5125 9075);
DISPLAY 1.021277 (5125 9075);
DISPLAY INVISIBLE (5125 9075);
FORCEPROP 0 LASTPIN (4950 8600) $PN 1
J 2
(4940 8610);
DISPLAY 0.680851 (4940 8610);
PAINT MONO (4940 8610);
FORCEPROP 0 LASTPIN (5600 8600) $PN 6
J 0
(5610 8610);
DISPLAY 0.680851 (5610 8610);
PAINT MONO (5610 8610);
FORCEPROP 0 LASTPIN (4950 8500) $PN 3
J 2
(4940 8510);
DISPLAY 0.680851 (4940 8510);
PAINT MONO (4940 8510);
FORCEPROP 0 LASTPIN (5600 8500) $PN 4
J 0
(5610 8510);
DISPLAY 0.680851 (5610 8510);
PAINT MONO (5610 8510);
FORCEPROP 0 LASTPIN (4950 8550) $PN 2
J 2
(4940 8560);
DISPLAY 0.680851 (4940 8560);
PAINT MONO (4940 8560);
FORCEPROP 0 LASTPIN (5600 8550) $PN 5
J 0
(5610 8560);
DISPLAY 0.680851 (5610 8560);
PAINT MONO (5610 8560);
FORCEPROP 2 LAST VALUE 74LVC2G07DW-7
J 0
(5125 8975);
DISPLAY 1.021277 (5125 8975);
FORCEPROP 1 LAST MATERIAL IC
J 0
(5106 8657);
DISPLAY 0.723404 (5106 8657);
PAINT GREEN (5106 8657);
FORCEPROP 2 LAST PART_TYPE SMLF
J 0
(5125 9025);
DISPLAY 1.021277 (5125 9025);
FORCEPROP 1 LAST NEEDS_NO_SIZE TRUE
J 0
(5275 8550);
DISPLAY 0.723404 (5275 8550);
PAINT GREEN (5275 8550);
DISPLAY INVISIBLE (5275 8550);
FORCEPROP 1 LAST CDS_LMAN_SYM_OUTLINE -175,100,175,-100
J 0
(5275 8550);
DISPLAY 0.468085 (5275 8550);
PAINT GREEN (5275 8550);
DISPLAY INVISIBLE (5275 8550);
FORCEPROP 2 LAST CDS_LIB pure_quanta
J 0
(5275 8550);
DISPLAY INVISIBLE (5275 8550);
FORCEPROP 1 LAST PATH I26
J 0
(5275 8550);
DISPLAY 0.723404 (5275 8550);
PAINT GREEN (5275 8550);
DISPLAY INVISIBLE (5275 8550);
FORCEPROP 1 LAST PART_NUMBER AL002G07003
J 0
(5106 8784);
DISPLAY 0.723404 (5106 8784);
PAINT GREEN (5106 8784);
DISPLAY INVISIBLE (5106 8784);
FORCEADD UNIVERSAL_GND..1
(4875 9175);
FORCEPROP 3 LASTPIN (4875 9225) SIG_NAME GND\g
J 0
(4885 9235);
DISPLAY 0.659574 (4885 9235);
PAINT MONO (4885 9235);
DISPLAY INVISIBLE (4885 9235);
FORCEPROP 2 LAST CDS_LIB pure_quanta_power
J 0
(4875 9175);
PAINT MONO (4875 9175);
DISPLAY INVISIBLE (4875 9175);
FORCEPROP 1 LAST HDL_POWER GND
J 1
(4900 9100);
DISPLAY 0.872340 (4900 9100);
PAINT GREEN (4900 9100);
DISPLAY INVISIBLE (4900 9100);
FORCEPROP 1 LAST PATH I27
J 0
(4950 9175);
DISPLAY 0.872340 (4950 9175);
PAINT AQUA (4950 9175);
DISPLAY INVISIBLE (4950 9175);
FORCEADD Q_RES..2
(4225 9750);
FORCEPROP 1 LAST LOCATION R1907
J 0
(4270 9875);
DISPLAY 0.978723 (4270 9875);
FORCEPROP 0 LAST $SEC 1
J 0
(4275 9925);
DISPLAY 0.680851 (4275 9925);
PAINT MONO (4275 9925);
DISPLAY INVISIBLE (4275 9925);
FORCEPROP 0 LAST CDS_SEC 1
J 0
(4275 9925);
DISPLAY 1.021277 (4275 9925);
DISPLAY INVISIBLE (4275 9925);
FORCEPROP 1 LASTPIN (4225 9850) $PN 1
J 0
(4230 9812);
DISPLAY 0.787234 (4230 9812);
PAINT MONO (4230 9812);
FORCEPROP 1 LASTPIN (4225 9650) $PN 2
J 0
(4230 9660);
DISPLAY 0.787234 (4230 9660);
PAINT MONO (4230 9660);
FORCEPROP 1 LAST MATERIAL CHIP
J 0
(4265 9675);
DISPLAY 0.638298 (4265 9675);
FORCEPROP 1 LAST PACK_TYPE 0402LF
J 0
(4265 9625);
DISPLAY 0.638298 (4265 9625);
FORCEPROP 1 LAST TOLERANCE 1%
J 0
(4270 9775);
DISPLAY 0.638298 (4270 9775);
FORCEPROP 1 LAST VALUE 1K
J 0
(4270 9825);
DISPLAY 0.638298 (4270 9825);
FORCEPROP 1 LAST WATTAGE 1/16W
J 0
(4265 9725);
DISPLAY 0.638298 (4265 9725);
FORCEPROP 2 LAST CDS_LIB pure_quanta
J 0
(4225 9750);
DISPLAY INVISIBLE (4225 9750);
FORCEPROP 1 LAST PATH I28
J 0
(4275 9925);
DISPLAY 0.978723 (4275 9925);
PAINT WHITE (4275 9925);
DISPLAY INVISIBLE (4275 9925);
FORCEPROP 1 LAST PART_NUMBER CS21002FB06
J 0
(4265 9625);
DISPLAY 0.638298 (4265 9625);
DISPLAY INVISIBLE (4265 9625);
FORCEADD 74LVC2G07DW7..1
(5275 9450);
FORCEPROP 1 LAST LOCATION U211
J 0
(5106 9831);
DISPLAY 0.723404 (5106 9831);
PAINT GREEN (5106 9831);
FORCEPROP 0 LAST $SEC 1
J 0
(5125 9975);
DISPLAY 0.680851 (5125 9975);
PAINT MONO (5125 9975);
DISPLAY INVISIBLE (5125 9975);
FORCEPROP 0 LAST CDS_SEC 1
J 0
(5125 9975);
DISPLAY 1.021277 (5125 9975);
DISPLAY INVISIBLE (5125 9975);
FORCEPROP 0 LASTPIN (4950 9500) $PN 1
J 2
(4940 9510);
DISPLAY 0.680851 (4940 9510);
PAINT MONO (4940 9510);
FORCEPROP 0 LASTPIN (5600 9500) $PN 6
J 0
(5610 9510);
DISPLAY 0.680851 (5610 9510);
PAINT MONO (5610 9510);
FORCEPROP 0 LASTPIN (4950 9400) $PN 3
J 2
(4940 9410);
DISPLAY 0.680851 (4940 9410);
PAINT MONO (4940 9410);
FORCEPROP 0 LASTPIN (5600 9400) $PN 4
J 0
(5610 9410);
DISPLAY 0.680851 (5610 9410);
PAINT MONO (5610 9410);
FORCEPROP 0 LASTPIN (4950 9450) $PN 2
J 2
(4940 9460);
DISPLAY 0.680851 (4940 9460);
PAINT MONO (4940 9460);
FORCEPROP 0 LASTPIN (5600 9450) $PN 5
J 0
(5610 9460);
DISPLAY 0.680851 (5610 9460);
PAINT MONO (5610 9460);
FORCEPROP 1 LAST MATERIAL IC
J 0
(5106 9557);
DISPLAY 0.723404 (5106 9557);
PAINT GREEN (5106 9557);
FORCEPROP 2 LAST VALUE 74LVC2G07DW-7
J 0
(5125 9875);
DISPLAY 1.021277 (5125 9875);
FORCEPROP 2 LAST PART_TYPE SMLF
J 0
(5125 9925);
DISPLAY 1.021277 (5125 9925);
FORCEPROP 1 LAST NEEDS_NO_SIZE TRUE
J 0
(5275 9450);
DISPLAY 0.723404 (5275 9450);
PAINT GREEN (5275 9450);
DISPLAY INVISIBLE (5275 9450);
FORCEPROP 1 LAST CDS_LMAN_SYM_OUTLINE -175,100,175,-100
J 0
(5275 9450);
DISPLAY 0.468085 (5275 9450);
PAINT GREEN (5275 9450);
DISPLAY INVISIBLE (5275 9450);
FORCEPROP 2 LAST CDS_LIB pure_quanta
J 0
(5275 9450);
DISPLAY INVISIBLE (5275 9450);
FORCEPROP 1 LAST PATH I29
J 0
(5275 9450);
DISPLAY 0.723404 (5275 9450);
PAINT GREEN (5275 9450);
DISPLAY INVISIBLE (5275 9450);
FORCEPROP 1 LAST PART_NUMBER AL002G07003
J 0
(5106 9684);
DISPLAY 0.723404 (5106 9684);
PAINT GREEN (5106 9684);
DISPLAY INVISIBLE (5106 9684);
FORCEADD OFFPAGE..1
(2125 11825);
PAINT AQUA (2125 11825);
FORCEPROP 2 LAST $XR3 248 
J 0
(1814 11789);
DISPLAY 0.638298 (1814 11789);
PAINT MONO (1814 11789);
FORCEPROP 2 LAST $XR2 135 
J 0
(1694 11825);
DISPLAY 0.638298 (1694 11825);
PAINT MONO (1694 11825);
FORCEPROP 2 LAST $XR1 83 
J 0
(1814 11825);
DISPLAY 0.638298 (1814 11825);
PAINT MONO (1814 11825);
FORCEPROP 2 LAST $XR0 80 
J 0
(1904 11825);
DISPLAY 0.638298 (1904 11825);
PAINT MONO (1904 11825);
FORCEPROP 2 LAST CDS_LIB standard
J 0
(2125 11825);
DISPLAY INVISIBLE (2125 11825);
FORCEPROP 1 LAST OFFPAGE TRUE
J 0
(2450 11700);
DISPLAY 0.872340 (2450 11700);
PAINT AQUA (2450 11700);
DISPLAY INVISIBLE (2450 11700);
FORCEPROP 1 LAST COMMENT_BODY TRUE
J 0
(2250 11725);
DISPLAY 0.872340 (2250 11725);
PAINT GREEN (2250 11725);
DISPLAY INVISIBLE (2250 11725);
FORCEPROP 2 LAST PATH I3
J 0
(1875 11875);
DISPLAY 0.680851 (1875 11875);
DISPLAY INVISIBLE (1875 11875);
FORCEADD Q_CAP..1
(5950 8375);
FORCEPROP 1 LAST LOCATION C593
J 0
(6000 8475);
DISPLAY 0.978723 (6000 8475);
FORCEPROP 2 LAST $SEC 1
J 0
(6000 8575);
DISPLAY 0.680851 (6000 8575);
PAINT MONO (6000 8575);
DISPLAY INVISIBLE (6000 8575);
FORCEPROP 2 LAST CDS_SEC 1
J 0
(6000 8575);
DISPLAY 1.021277 (6000 8575);
DISPLAY INVISIBLE (6000 8575);
FORCEPROP 1 LASTPIN (5950 8475) $PN 1
J 0
(5960 8455);
DISPLAY 0.787234 (5960 8455);
FORCEPROP 1 LASTPIN (5950 8275) $PN 2
J 0
(5960 8255);
DISPLAY 0.787234 (5960 8255);
FORCEPROP 1 LAST PACK_TYPE 0402
J 0
(6000 8175);
DISPLAY 0.510638 (6000 8175);
FORCEPROP 1 LAST VALUE 0.1UF
J 0
(6000 8425);
DISPLAY 0.510638 (6000 8425);
FORCEPROP 1 LAST VOLTAGE 25V
J 0
(6000 8375);
DISPLAY 0.510638 (6000 8375);
FORCEPROP 1 LAST TOLERANCE 10%
J 0
(6000 8325);
DISPLAY 0.510638 (6000 8325);
FORCEPROP 1 LAST MATERIAL X7R
J 0
(6000 8275);
DISPLAY 0.510638 (6000 8275);
FORCEPROP 2 LAST CDS_LIB pure_quanta
J 0
(5950 8375);
PAINT MONO (5950 8375);
DISPLAY INVISIBLE (5950 8375);
FORCEPROP 1 LAST PATH I30
J 0
(6000 8525);
DISPLAY 0.978723 (6000 8525);
PAINT WHITE (6000 8525);
DISPLAY INVISIBLE (6000 8525);
FORCEPROP 1 LAST PART_NUMBER CH4104K1B00
J 0
(6000 8225);
DISPLAY 0.510638 (6000 8225);
DISPLAY INVISIBLE (6000 8225);
FORCEADD UNIVERSAL_POWER..1
(5950 8650);
FORCEPROP 3 LASTPIN (5950 8600) SIG_NAME P3V3_AUX\g
J 0
(5960 8610);
DISPLAY 0.659574 (5960 8610);
PAINT MONO (5960 8610);
DISPLAY INVISIBLE (5960 8610);
FORCEPROP 1 LAST HDL_POWER P3V3_AUX
J 1
(5950 8700);
DISPLAY 0.872340 (5950 8700);
PAINT GREEN (5950 8700);
FORCEPROP 2 LAST CDS_LIB pure_quanta_power
J 0
(5950 8650);
PAINT MONO (5950 8650);
DISPLAY INVISIBLE (5950 8650);
FORCEPROP 1 LAST PATH I31
J 0
(6000 8675);
DISPLAY 0.872340 (6000 8675);
PAINT AQUA (6000 8675);
DISPLAY INVISIBLE (6000 8675);
FORCEADD UNIVERSAL_GND..1
(5950 9075);
FORCEPROP 3 LASTPIN (5950 9125) SIG_NAME GND\g
J 0
(5960 9135);
DISPLAY 0.659574 (5960 9135);
PAINT MONO (5960 9135);
DISPLAY INVISIBLE (5960 9135);
FORCEPROP 2 LAST CDS_LIB pure_quanta_power
J 0
(5950 9075);
PAINT MONO (5950 9075);
DISPLAY INVISIBLE (5950 9075);
FORCEPROP 1 LAST HDL_POWER GND
J 1
(5975 9000);
DISPLAY 0.872340 (5975 9000);
PAINT GREEN (5975 9000);
DISPLAY INVISIBLE (5975 9000);
FORCEPROP 1 LAST PATH I32
J 0
(6025 9075);
DISPLAY 0.872340 (6025 9075);
PAINT AQUA (6025 9075);
DISPLAY INVISIBLE (6025 9075);
FORCEADD Q_CAP..1
(5950 9275);
FORCEPROP 1 LAST LOCATION C592
J 0
(6000 9375);
DISPLAY 0.978723 (6000 9375);
FORCEPROP 2 LAST $SEC 1
J 0
(6000 9475);
DISPLAY 0.680851 (6000 9475);
PAINT MONO (6000 9475);
DISPLAY INVISIBLE (6000 9475);
FORCEPROP 2 LAST CDS_SEC 1
J 0
(6000 9475);
DISPLAY 1.021277 (6000 9475);
DISPLAY INVISIBLE (6000 9475);
FORCEPROP 1 LASTPIN (5950 9375) $PN 1
J 0
(5960 9355);
DISPLAY 0.787234 (5960 9355);
FORCEPROP 1 LASTPIN (5950 9175) $PN 2
J 0
(5960 9155);
DISPLAY 0.787234 (5960 9155);
FORCEPROP 1 LAST PACK_TYPE 0402
J 0
(6000 9075);
DISPLAY 0.510638 (6000 9075);
FORCEPROP 1 LAST TOLERANCE 10%
J 0
(6000 9225);
DISPLAY 0.510638 (6000 9225);
FORCEPROP 1 LAST MATERIAL X7R
J 0
(6000 9175);
DISPLAY 0.510638 (6000 9175);
FORCEPROP 1 LAST VALUE 0.1UF
J 0
(6000 9325);
DISPLAY 0.510638 (6000 9325);
FORCEPROP 1 LAST VOLTAGE 25V
J 0
(6000 9275);
DISPLAY 0.510638 (6000 9275);
FORCEPROP 2 LAST CDS_LIB pure_quanta
J 0
(5950 9275);
PAINT MONO (5950 9275);
DISPLAY INVISIBLE (5950 9275);
FORCEPROP 1 LAST PATH I33
J 0
(6000 9425);
DISPLAY 0.978723 (6000 9425);
PAINT WHITE (6000 9425);
DISPLAY INVISIBLE (6000 9425);
FORCEPROP 1 LAST PART_NUMBER CH4104K1B00
J 0
(6000 9125);
DISPLAY 0.510638 (6000 9125);
DISPLAY INVISIBLE (6000 9125);
FORCEADD UNIVERSAL_POWER..1
(5950 9550);
FORCEPROP 3 LASTPIN (5950 9500) SIG_NAME P3V3_AUX\g
J 0
(5960 9510);
DISPLAY 0.659574 (5960 9510);
PAINT MONO (5960 9510);
DISPLAY INVISIBLE (5960 9510);
FORCEPROP 1 LAST HDL_POWER P3V3_AUX
J 1
(5950 9600);
DISPLAY 0.872340 (5950 9600);
PAINT GREEN (5950 9600);
FORCEPROP 2 LAST CDS_LIB pure_quanta_power
J 0
(5950 9550);
PAINT MONO (5950 9550);
DISPLAY INVISIBLE (5950 9550);
FORCEPROP 1 LAST PATH I34
J 0
(6000 9575);
DISPLAY 0.872340 (6000 9575);
PAINT AQUA (6000 9575);
DISPLAY INVISIBLE (6000 9575);
FORCEADD GND..1
(6025 9950);
FORCEPROP 3 LASTPIN (6025 10000) SIG_NAME GND\g
J 0
(6035 10010);
DISPLAY 0.659574 (6035 10010);
PAINT MONO (6035 10010);
DISPLAY INVISIBLE (6035 10010);
FORCEPROP 2 LAST CDS_LIB pure_quanta_power
J 0
(6025 9950);
DISPLAY INVISIBLE (6025 9950);
FORCEPROP 1 LAST SIZE 1B
J 0
(6100 9900);
DISPLAY 0.872340 (6100 9900);
PAINT GREEN (6100 9900);
DISPLAY INVISIBLE (6100 9900);
FORCEPROP 1 LAST HDL_POWER GND
J 0
(6025 10100);
DISPLAY 0.872340 (6025 10100);
PAINT GREEN (6025 10100);
DISPLAY INVISIBLE (6025 10100);
FORCEPROP 1 LAST PATH I35
J 0
(6100 9950);
DISPLAY 0.872340 (6100 9950);
PAINT AQUA (6100 9950);
DISPLAY INVISIBLE (6100 9950);
FORCEADD Q_RES..2
(6025 10200);
FORCEPROP 1 LAST LOCATION PR3788
J 0
(6075 10275);
DISPLAY 0.638298 (6075 10275);
FORCEPROP 0 LAST $SEC 1
J 0
(6075 10325);
DISPLAY 0.680851 (6075 10325);
PAINT MONO (6075 10325);
DISPLAY INVISIBLE (6075 10325);
FORCEPROP 0 LAST CDS_SEC 1
J 0
(6075 10325);
DISPLAY 1.021277 (6075 10325);
DISPLAY INVISIBLE (6075 10325);
FORCEPROP 1 LASTPIN (6025 10300) $PN 1
J 0
(6030 10262);
DISPLAY 0.787234 (6030 10262);
PAINT MONO (6030 10262);
DISPLAY INVISIBLE (6030 10262);
FORCEPROP 1 LASTPIN (6025 10100) $PN 2
J 0
(6030 10110);
DISPLAY 0.787234 (6030 10110);
PAINT MONO (6030 10110);
DISPLAY INVISIBLE (6030 10110);
FORCEPROP 0 LAST ROOM NIC_P12V_MAM_TIC_BOM1
J 0
(6075 10075);
DISPLAY 0.446809 (6075 10075);
PAINT RED (6075 10075);
FORCEPROP 1 LAST MATERIAL CHIP
J 0
(6075 10175);
DISPLAY 0.404255 (6075 10175);
FORCEPROP 1 LAST WATTAGE 1/16W
J 0
(6075 10200);
DISPLAY 0.404255 (6075 10200);
FORCEPROP 1 LAST VALUE 15K
J 0
(6075 10250);
DISPLAY 0.404255 (6075 10250);
FORCEPROP 1 LAST TOLERANCE 1%
J 0
(6075 10225);
DISPLAY 0.404255 (6075 10225);
FORCEPROP 1 LAST PACK_TYPE 0402LF
J 0
(6075 10125);
DISPLAY 0.404255 (6075 10125);
FORCEPROP 2 LAST CDS_LIB pure_quanta
J 0
(6025 10200);
DISPLAY INVISIBLE (6025 10200);
FORCEPROP 1 LAST PATH I36
J 0
(6075 10375);
DISPLAY 0.978723 (6075 10375);
PAINT WHITE (6075 10375);
DISPLAY INVISIBLE (6075 10375);
FORCEPROP 1 LAST PART_NUMBER CS31502FB05
J 0
(6075 10150);
DISPLAY 0.404255 (6075 10150);
DISPLAY INVISIBLE (6075 10150);
FORCEADD GND..1
(4475 10275);
FORCEPROP 3 LASTPIN (4475 10325) SIG_NAME GND\g
J 0
(4485 10335);
DISPLAY 0.659574 (4485 10335);
PAINT MONO (4485 10335);
DISPLAY INVISIBLE (4485 10335);
FORCEPROP 2 LAST CDS_LIB pure_quanta_power
J 0
(4475 10275);
DISPLAY INVISIBLE (4475 10275);
FORCEPROP 1 LAST SIZE 1B
J 0
(4550 10225);
DISPLAY 0.872340 (4550 10225);
PAINT GREEN (4550 10225);
DISPLAY INVISIBLE (4550 10225);
FORCEPROP 1 LAST HDL_POWER GND
J 0
(4475 10425);
DISPLAY 0.872340 (4475 10425);
PAINT GREEN (4475 10425);
DISPLAY INVISIBLE (4475 10425);
FORCEPROP 1 LAST PATH I37
J 0
(4550 10275);
DISPLAY 0.872340 (4550 10275);
PAINT AQUA (4550 10275);
DISPLAY INVISIBLE (4550 10275);
FORCEADD GND..1
(4225 11525);
FORCEPROP 3 LASTPIN (4225 11575) SIG_NAME GND\g
J 0
(4235 11585);
DISPLAY 0.659574 (4235 11585);
PAINT MONO (4235 11585);
DISPLAY INVISIBLE (4235 11585);
FORCEPROP 1 LAST SIZE 1B
J 0
(4300 11475);
DISPLAY 0.872340 (4300 11475);
PAINT GREEN (4300 11475);
DISPLAY INVISIBLE (4300 11475);
FORCEPROP 2 LAST CDS_LIB pure_quanta_power
J 0
(4225 11525);
DISPLAY INVISIBLE (4225 11525);
FORCEPROP 1 LAST HDL_POWER GND
J 0
(4225 11675);
DISPLAY 0.872340 (4225 11675);
PAINT GREEN (4225 11675);
DISPLAY INVISIBLE (4225 11675);
FORCEPROP 1 LAST PATH I38
J 0
(4300 11525);
DISPLAY 0.872340 (4300 11525);
PAINT AQUA (4300 11525);
DISPLAY INVISIBLE (4300 11525);
FORCEADD GND..1
(4975 11900);
FORCEPROP 3 LASTPIN (4975 11950) SIG_NAME GND\g
J 0
(4985 11960);
DISPLAY 0.659574 (4985 11960);
PAINT MONO (4985 11960);
DISPLAY INVISIBLE (4985 11960);
FORCEPROP 1 LAST SIZE 1B
J 0
(5050 11850);
DISPLAY 0.872340 (5050 11850);
PAINT GREEN (5050 11850);
DISPLAY INVISIBLE (5050 11850);
FORCEPROP 2 LAST CDS_LIB pure_quanta_power
J 0
(4975 11900);
DISPLAY INVISIBLE (4975 11900);
FORCEPROP 1 LAST HDL_POWER GND
J 0
(4975 12050);
DISPLAY 0.872340 (4975 12050);
PAINT GREEN (4975 12050);
DISPLAY INVISIBLE (4975 12050);
FORCEPROP 1 LAST PATH I39
J 0
(5050 11900);
DISPLAY 0.872340 (5050 11900);
PAINT AQUA (5050 11900);
DISPLAY INVISIBLE (5050 11900);
FORCEADD Q_RES..1
(5500 10825);
FORCEPROP 1 LAST LOCATION R3784
J 0
(5275 10825);
DISPLAY 0.638298 (5275 10825);
FORCEPROP 0 LAST $SEC 1
J 0
(5450 10925);
DISPLAY 0.680851 (5450 10925);
PAINT MONO (5450 10925);
DISPLAY INVISIBLE (5450 10925);
FORCEPROP 0 LAST CDS_SEC 1
J 0
(5450 10925);
DISPLAY 1.021277 (5450 10925);
DISPLAY INVISIBLE (5450 10925);
FORCEPROP 1 LASTPIN (5400 10825) $PN 1
J 0
(5412 10837);
DISPLAY 0.787234 (5412 10837);
PAINT MONO (5412 10837);
DISPLAY INVISIBLE (5412 10837);
FORCEPROP 1 LASTPIN (5600 10825) $PN 2
J 0
(5562 10837);
DISPLAY 0.787234 (5562 10837);
PAINT MONO (5562 10837);
DISPLAY INVISIBLE (5562 10837);
FORCEPROP 1 LAST WATTAGE 1/16W
J 2
(5700 10750);
DISPLAY 0.510638 (5700 10750);
FORCEPROP 1 LAST VALUE 0
J 2
(5650 10825);
DISPLAY 0.510638 (5650 10825);
FORCEPROP 1 LAST TOLERANCE 5%
J 0
(5675 10825);
DISPLAY 0.510638 (5675 10825);
FORCEPROP 1 LAST MATERIAL CHIP
J 0
(5425 10750);
DISPLAY 0.510638 (5425 10750);
FORCEPROP 1 LAST PACK_TYPE 0402LF
J 0
(5750 10825);
DISPLAY 0.510638 (5750 10825);
FORCEPROP 0 LAST ROOM NIC_P12V_MAM_TIC_BOM1
J 0
(5275 10875);
DISPLAY 0.553191 (5275 10875);
PAINT RED (5275 10875);
FORCEPROP 2 LAST CDS_LIB pure_quanta
J 0
(5500 10825);
DISPLAY INVISIBLE (5500 10825);
FORCEPROP 1 LAST PATH I40
J 0
(5450 10975);
DISPLAY 0.978723 (5450 10975);
PAINT WHITE (5450 10975);
DISPLAY INVISIBLE (5450 10975);
FORCEPROP 1 LAST PART_NUMBER CS00002JB13
J 0
(5425 10775);
DISPLAY 0.510638 (5425 10775);
DISPLAY INVISIBLE (5425 10775);
FORCEADD GND..1
(5450 11075);
FORCEPROP 3 LASTPIN (5450 11125) SIG_NAME GND\g
J 0
(5460 11135);
DISPLAY 0.659574 (5460 11135);
PAINT MONO (5460 11135);
DISPLAY INVISIBLE (5460 11135);
FORCEPROP 1 LAST SIZE 1B
J 0
(5525 11025);
DISPLAY 0.872340 (5525 11025);
PAINT GREEN (5525 11025);
DISPLAY INVISIBLE (5525 11025);
FORCEPROP 2 LAST CDS_LIB pure_quanta_power
J 0
(5450 11075);
DISPLAY INVISIBLE (5450 11075);
FORCEPROP 1 LAST HDL_POWER GND
J 0
(5450 11225);
DISPLAY 0.872340 (5450 11225);
PAINT GREEN (5450 11225);
DISPLAY INVISIBLE (5450 11225);
FORCEPROP 1 LAST PATH I41
J 0
(5525 11075);
DISPLAY 0.872340 (5525 11075);
PAINT AQUA (5525 11075);
DISPLAY INVISIBLE (5525 11075);
FORCEADD Q_RES..2
(6025 10475);
FORCEPROP 1 LAST LOCATION PR3787
J 0
(6075 10550);
DISPLAY 0.638298 (6075 10550);
FORCEPROP 0 LAST $SEC 1
J 0
(6075 10600);
DISPLAY 0.680851 (6075 10600);
PAINT MONO (6075 10600);
DISPLAY INVISIBLE (6075 10600);
FORCEPROP 0 LAST CDS_SEC 1
J 0
(6075 10600);
DISPLAY 1.021277 (6075 10600);
DISPLAY INVISIBLE (6075 10600);
FORCEPROP 1 LASTPIN (6025 10575) $PN 1
J 0
(6030 10537);
DISPLAY 0.787234 (6030 10537);
PAINT MONO (6030 10537);
DISPLAY INVISIBLE (6030 10537);
FORCEPROP 1 LASTPIN (6025 10375) $PN 2
J 0
(6030 10385);
DISPLAY 0.787234 (6030 10385);
PAINT MONO (6030 10385);
DISPLAY INVISIBLE (6030 10385);
FORCEPROP 0 LAST ROOM NIC_P12V_MAM_TIC_BOM1
J 0
(5575 10375);
DISPLAY 0.446809 (5575 10375);
PAINT RED (5575 10375);
FORCEPROP 1 LAST MATERIAL CHIP
J 0
(6075 10450);
DISPLAY 0.404255 (6075 10450);
FORCEPROP 1 LAST WATTAGE 1/16W
J 0
(6075 10475);
DISPLAY 0.404255 (6075 10475);
FORCEPROP 1 LAST VALUE 6.8K
J 0
(6075 10525);
DISPLAY 0.404255 (6075 10525);
FORCEPROP 1 LAST TOLERANCE 1%
J 0
(6075 10500);
DISPLAY 0.404255 (6075 10500);
FORCEPROP 1 LAST PACK_TYPE 0402LF
J 0
(6075 10400);
DISPLAY 0.404255 (6075 10400);
FORCEPROP 2 LAST CDS_LIB pure_quanta
J 0
(6025 10475);
DISPLAY INVISIBLE (6025 10475);
FORCEPROP 1 LAST PATH I42
J 0
(6075 10650);
DISPLAY 0.978723 (6075 10650);
PAINT WHITE (6075 10650);
DISPLAY INVISIBLE (6075 10650);
FORCEPROP 1 LAST PART_NUMBER CS26802FB02
J 0
(6075 10425);
DISPLAY 0.404255 (6075 10425);
DISPLAY INVISIBLE (6075 10425);
FORCEADD Q_RES..2
(6025 11150);
FORCEPROP 1 LAST LOCATION PR3786
J 0
(6075 11225);
DISPLAY 0.638298 (6075 11225);
FORCEPROP 0 LAST $SEC 1
J 0
(6075 11275);
DISPLAY 0.680851 (6075 11275);
PAINT MONO (6075 11275);
DISPLAY INVISIBLE (6075 11275);
FORCEPROP 0 LAST CDS_SEC 1
J 0
(6075 11275);
DISPLAY 1.021277 (6075 11275);
DISPLAY INVISIBLE (6075 11275);
FORCEPROP 1 LASTPIN (6025 11250) $PN 1
J 0
(6030 11212);
DISPLAY 0.787234 (6030 11212);
PAINT MONO (6030 11212);
DISPLAY INVISIBLE (6030 11212);
FORCEPROP 1 LASTPIN (6025 11050) $PN 2
J 0
(6030 11060);
DISPLAY 0.787234 (6030 11060);
PAINT MONO (6030 11060);
DISPLAY INVISIBLE (6030 11060);
FORCEPROP 1 LAST VALUE 160K
J 0
(6075 11200);
DISPLAY 0.404255 (6075 11200);
FORCEPROP 1 LAST TOLERANCE 1%
J 0
(6075 11175);
DISPLAY 0.404255 (6075 11175);
FORCEPROP 1 LAST WATTAGE 1/16W
J 0
(6075 11150);
DISPLAY 0.404255 (6075 11150);
FORCEPROP 1 LAST MATERIAL CHIP
J 0
(6075 11125);
DISPLAY 0.404255 (6075 11125);
FORCEPROP 0 LAST ROOM NIC_P12V_MAM_TIC_BOM1
J 0
(5950 11050);
DISPLAY 0.361702 (5950 11050);
PAINT RED (5950 11050);
FORCEPROP 1 LAST PACK_TYPE 0402LF
J 0
(6075 11075);
DISPLAY 0.404255 (6075 11075);
FORCEPROP 2 LAST CDS_LIB pure_quanta
J 0
(6025 11150);
DISPLAY INVISIBLE (6025 11150);
FORCEPROP 1 LAST PATH I43
J 0
(6075 11325);
DISPLAY 0.978723 (6075 11325);
PAINT WHITE (6075 11325);
DISPLAY INVISIBLE (6075 11325);
FORCEPROP 1 LAST PART_NUMBER CS41602FB05
J 0
(6075 11100);
DISPLAY 0.404255 (6075 11100);
DISPLAY INVISIBLE (6075 11100);
FORCEADD UNIVERSAL_POWER..1
(5450 11800);
FORCEPROP 3 LASTPIN (5450 11750) SIG_NAME P12V_AUX\g
J 0
(5460 11760);
DISPLAY 0.659574 (5460 11760);
PAINT MONO (5460 11760);
DISPLAY INVISIBLE (5460 11760);
FORCEPROP 1 LAST HDL_POWER P12V_AUX
J 1
(5450 11850);
DISPLAY 0.872340 (5450 11850);
PAINT GREEN (5450 11850);
FORCEPROP 2 LAST CDS_LIB pure_quanta_power
J 0
(5450 11800);
DISPLAY INVISIBLE (5450 11800);
FORCEPROP 1 LAST PATH I44
J 0
(5500 11825);
DISPLAY 0.872340 (5500 11825);
PAINT AQUA (5500 11825);
DISPLAY INVISIBLE (5500 11825);
FORCEADD Q_CAP..1
(5675 11450);
FORCEPROP 1 LAST LOCATION PC2079
J 0
(5725 11525);
DISPLAY 0.638298 (5725 11525);
FORCEPROP 0 LAST $SEC 1
J 0
(5730 11592);
DISPLAY INVISIBLE (5730 11592);
FORCEPROP 0 LAST CDS_SEC 1
J 0
(5730 11592);
DISPLAY INVISIBLE (5730 11592);
FORCEPROP 1 LASTPIN (5675 11550) $PN 1
J 0
(5685 11530);
DISPLAY 0.787234 (5685 11530);
PAINT MONO (5685 11530);
DISPLAY INVISIBLE (5685 11530);
FORCEPROP 1 LASTPIN (5675 11350) $PN 2
J 0
(5685 11330);
DISPLAY 0.787234 (5685 11330);
PAINT MONO (5685 11330);
DISPLAY INVISIBLE (5685 11330);
FORCEPROP 1 LAST VALUE 1UF
J 0
(5725 11500);
DISPLAY 0.510638 (5725 11500);
FORCEPROP 1 LAST VOLTAGE 25V
J 0
(5725 11475);
DISPLAY 0.510638 (5725 11475);
FORCEPROP 1 LAST MATERIAL X6S
J 0
(5725 11450);
DISPLAY 0.510638 (5725 11450);
FORCEPROP 1 LAST PACK_TYPE C0402
J 0
(5725 11425);
DISPLAY 0.510638 (5725 11425);
FORCEPROP 2 LAST CDS_LIB pure_quanta
J 0
(5675 11450);
DISPLAY INVISIBLE (5675 11450);
FORCEPROP 1 LAST TOLERANCE 10%
J 0
(5725 11400);
DISPLAY 0.638298 (5725 11400);
DISPLAY INVISIBLE (5725 11400);
FORCEPROP 1 LAST PATH I45
J 0
(5725 11600);
DISPLAY 0.978723 (5725 11600);
PAINT WHITE (5725 11600);
DISPLAY INVISIBLE (5725 11600);
FORCEPROP 1 LAST PART_NUMBER CH5104KEB02
J 0
(5725 11400);
DISPLAY 0.510638 (5725 11400);
DISPLAY INVISIBLE (5725 11400);
FORCEADD Q_RES..1
(6850 8900);
FORCEPROP 1 LAST LOCATION R1148
J 0
(6650 8900);
DISPLAY 0.638298 (6650 8900);
FORCEPROP 2 LAST $SEC 1
J 0
(6800 9100);
DISPLAY 0.680851 (6800 9100);
PAINT MONO (6800 9100);
DISPLAY INVISIBLE (6800 9100);
FORCEPROP 2 LAST CDS_SEC 1
J 0
(6800 9100);
DISPLAY 1.021277 (6800 9100);
DISPLAY INVISIBLE (6800 9100);
FORCEPROP 1 LASTPIN (6750 8900) $PN 1
J 0
(6762 8912);
DISPLAY 0.787234 (6762 8912);
FORCEPROP 1 LASTPIN (6950 8900) $PN 2
J 0
(6912 8912);
DISPLAY 0.787234 (6912 8912);
FORCEPROP 1 LAST TOLERANCE 5%
J 0
(7025 8900);
DISPLAY 0.404255 (7025 8900);
FORCEPROP 1 LAST WATTAGE 1/16W
J 2
(6975 8825);
DISPLAY 0.404255 (6975 8825);
FORCEPROP 1 LAST MATERIAL CHIP
J 0
(6775 8825);
DISPLAY 0.404255 (6775 8825);
FORCEPROP 1 LAST VALUE 0
J 2
(7000 8900);
DISPLAY 0.404255 (7000 8900);
FORCEPROP 1 LAST PACK_TYPE 0402LF
J 0
(7075 8900);
DISPLAY 0.404255 (7075 8900);
FORCEPROP 2 LAST CDS_LIB pure_quanta
J 0
(6850 8900);
PAINT MONO (6850 8900);
DISPLAY INVISIBLE (6850 8900);
FORCEPROP 1 LAST PATH I46
J 0
(6800 9050);
DISPLAY 0.978723 (6800 9050);
PAINT WHITE (6800 9050);
DISPLAY INVISIBLE (6800 9050);
FORCEPROP 1 LAST PART_NUMBER CS00002JB13
J 0
(6775 8850);
DISPLAY 0.404255 (6775 8850);
DISPLAY INVISIBLE (6775 8850);
FORCEADD Q_RES..2
(6875 10225);
FORCEPROP 1 LAST LOCATION PR5484
J 0
(6925 10275);
DISPLAY 0.638298 (6925 10275);
FORCEPROP 0 LAST $SEC 1
J 0
(6925 10375);
DISPLAY 0.680851 (6925 10375);
PAINT MONO (6925 10375);
DISPLAY INVISIBLE (6925 10375);
FORCEPROP 0 LAST CDS_SEC 1
J 0
(6925 10350);
DISPLAY INVISIBLE (6925 10350);
FORCEPROP 1 LASTPIN (6875 10325) $PN 1
J 0
(6880 10287);
DISPLAY 0.787234 (6880 10287);
PAINT MONO (6880 10287);
FORCEPROP 1 LASTPIN (6875 10125) $PN 2
J 0
(6880 10135);
DISPLAY 0.787234 (6880 10135);
PAINT MONO (6880 10135);
FORCEPROP 0 LAST ROOM NIC_P12V_MAM_TIC_BOM1
J 0
(6425 10125);
DISPLAY 0.446809 (6425 10125);
PAINT RED (6425 10125);
FORCEPROP 1 LAST TOLERANCE 1%
J 0
(6925 10225);
DISPLAY 0.510638 (6925 10225);
FORCEPROP 1 LAST MATERIAL CHIP
J 0
(6925 10175);
DISPLAY 0.510638 (6925 10175);
FORCEPROP 1 LAST PACK_TYPE 0402LF
J 0
(6925 10125);
DISPLAY 0.510638 (6925 10125);
FORCEPROP 1 LAST VALUE 30.1K
J 0
(6925 10250);
DISPLAY 0.510638 (6925 10250);
FORCEPROP 1 LAST WATTAGE 1/16W
J 0
(6925 10200);
DISPLAY 0.510638 (6925 10200);
FORCEPROP 2 LAST CDS_LIB pure_quanta
J 0
(6875 10225);
DISPLAY INVISIBLE (6875 10225);
FORCEPROP 1 LAST PATH I48
J 0
(6925 10400);
DISPLAY 0.978723 (6925 10400);
PAINT WHITE (6925 10400);
DISPLAY INVISIBLE (6925 10400);
FORCEPROP 1 LAST PART_NUMBER CS33012FB03
J 0
(6925 10150);
DISPLAY 0.510638 (6925 10150);
DISPLAY INVISIBLE (6925 10150);
FORCEADD GND..1
(6875 9925);
FORCEPROP 3 LASTPIN (6875 9975) SIG_NAME GND\g
J 0
(6885 9985);
DISPLAY 0.659574 (6885 9985);
PAINT MONO (6885 9985);
DISPLAY INVISIBLE (6885 9985);
FORCEPROP 2 LAST CDS_LIB pure_quanta_power
J 0
(6875 9925);
DISPLAY INVISIBLE (6875 9925);
FORCEPROP 1 LAST SIZE 1B
J 0
(6950 9875);
DISPLAY 0.872340 (6950 9875);
PAINT GREEN (6950 9875);
DISPLAY INVISIBLE (6950 9875);
FORCEPROP 1 LAST HDL_POWER GND
J 0
(6875 10075);
DISPLAY 0.872340 (6875 10075);
PAINT GREEN (6875 10075);
DISPLAY INVISIBLE (6875 10075);
FORCEPROP 1 LAST PATH I49
J 0
(6950 9925);
DISPLAY 0.872340 (6950 9925);
PAINT AQUA (6950 9925);
DISPLAY INVISIBLE (6950 9925);
FORCEADD GND..1
(3025 9650);
FORCEPROP 3 LASTPIN (3025 9700) SIG_NAME GND\g
J 0
(3035 9710);
DISPLAY 0.659574 (3035 9710);
PAINT MONO (3035 9710);
DISPLAY INVISIBLE (3035 9710);
FORCEPROP 2 LAST CDS_LIB pure_quanta_power
J 0
(3025 9650);
DISPLAY INVISIBLE (3025 9650);
FORCEPROP 1 LAST SIZE 1B
J 0
(3100 9600);
DISPLAY 0.872340 (3100 9600);
PAINT GREEN (3100 9600);
DISPLAY INVISIBLE (3100 9600);
FORCEPROP 1 LAST HDL_POWER GND
J 0
(3025 9800);
DISPLAY 0.872340 (3025 9800);
PAINT GREEN (3025 9800);
DISPLAY INVISIBLE (3025 9800);
FORCEPROP 1 LAST PATH I5
J 0
(3100 9650);
DISPLAY 0.872340 (3100 9650);
PAINT AQUA (3100 9650);
DISPLAY INVISIBLE (3100 9650);
FORCEADD MAX15090BEWIT..1
(7625 10725);
FORCEPROP 1 LAST LOCATION PU203
J 0
(7372 11453);
DISPLAY 0.723404 (7372 11453);
PAINT GREEN (7372 11453);
FORCEPROP 0 LAST $SEC 1
J 0
(7375 11600);
DISPLAY 0.680851 (7375 11600);
PAINT MONO (7375 11600);
DISPLAY INVISIBLE (7375 11600);
FORCEPROP 0 LAST CDS_SEC 1
J 0
(7375 11600);
DISPLAY 1.021277 (7375 11600);
DISPLAY INVISIBLE (7375 11600);
FORCEPROP 0 LASTPIN (7225 10425) $PN B1
J 2
(7215 10435);
DISPLAY 0.680851 (7215 10435);
PAINT MONO (7215 10435);
FORCEPROP 0 LASTPIN (8025 10425) $PN A7
J 0
(8035 10435);
DISPLAY 0.680851 (8035 10435);
PAINT MONO (8035 10435);
FORCEPROP 0 LASTPIN (7225 10325) $PN B7
J 2
(7215 10335);
DISPLAY 0.680851 (7215 10335);
PAINT MONO (7215 10335);
FORCEPROP 0 LASTPIN (8025 10625) $PN C7
J 0
(8035 10635);
DISPLAY 0.680851 (8035 10635);
PAINT MONO (8035 10635);
FORCEPROP 0 LASTPIN (8025 10825) $PN A6
J 0
(8035 10835);
DISPLAY 0.680851 (8035 10835);
PAINT MONO (8035 10835);
FORCEPROP 0 LASTPIN (8025 10325) $PN B2
J 0
(8035 10335);
DISPLAY 0.680851 (8035 10335);
PAINT MONO (8035 10335);
FORCEPROP 0 LASTPIN (8025 10275) $PN C1
J 0
(8035 10285);
DISPLAY 0.680851 (8035 10285);
PAINT MONO (8035 10285);
FORCEPROP 0 LASTPIN (8025 10225) $PN C2
J 0
(8035 10235);
DISPLAY 0.680851 (8035 10235);
PAINT MONO (8035 10235);
FORCEPROP 0 LASTPIN (7225 11225) $PN A3
J 2
(7215 11235);
DISPLAY 0.680851 (7215 11235);
PAINT MONO (7215 11235);
FORCEPROP 0 LASTPIN (7225 11175) $PN A5
J 2
(7215 11185);
DISPLAY 0.680851 (7215 11185);
PAINT MONO (7215 11185);
FORCEPROP 0 LASTPIN (7225 11125) $PN B3
J 2
(7215 11135);
DISPLAY 0.680851 (7215 11135);
PAINT MONO (7215 11135);
FORCEPROP 0 LASTPIN (7225 11075) $PN B5
J 2
(7215 11085);
DISPLAY 0.680851 (7215 11085);
PAINT MONO (7215 11085);
FORCEPROP 0 LASTPIN (7225 11025) $PN C3
J 2
(7215 11035);
DISPLAY 0.680851 (7215 11035);
PAINT MONO (7215 11035);
FORCEPROP 0 LASTPIN (7225 10975) $PN C5
J 2
(7215 10985);
DISPLAY 0.680851 (7215 10985);
PAINT MONO (7215 10985);
FORCEPROP 0 LASTPIN (7225 10925) $PN D5
J 2
(7215 10935);
DISPLAY 0.680851 (7215 10935);
PAINT MONO (7215 10935);
FORCEPROP 0 LASTPIN (8025 10525) $PN A1
J 0
(8035 10535);
DISPLAY 0.680851 (8035 10535);
PAINT MONO (8035 10535);
FORCEPROP 0 LASTPIN (8025 11225) $PN A4
J 0
(8035 11235);
DISPLAY 0.680851 (8035 11235);
PAINT MONO (8035 11235);
FORCEPROP 0 LASTPIN (8025 11175) $PN B4
J 0
(8035 11185);
DISPLAY 0.680851 (8035 11185);
PAINT MONO (8035 11185);
FORCEPROP 0 LASTPIN (8025 11125) $PN B6
J 0
(8035 11135);
DISPLAY 0.680851 (8035 11135);
PAINT MONO (8035 11135);
FORCEPROP 0 LASTPIN (8025 11075) $PN C4
J 0
(8035 11085);
DISPLAY 0.680851 (8035 11085);
PAINT MONO (8035 11085);
FORCEPROP 0 LASTPIN (8025 11025) $PN C6
J 0
(8035 11035);
DISPLAY 0.680851 (8035 11035);
PAINT MONO (8035 11035);
FORCEPROP 0 LASTPIN (8025 10975) $PN D4
J 0
(8035 10985);
DISPLAY 0.680851 (8035 10985);
PAINT MONO (8035 10985);
FORCEPROP 0 LASTPIN (8025 10925) $PN D6
J 0
(8035 10935);
DISPLAY 0.680851 (8035 10935);
PAINT MONO (8035 10935);
FORCEPROP 0 LASTPIN (7225 10525) $PN D3
J 2
(7215 10535);
DISPLAY 0.680851 (7215 10535);
PAINT MONO (7215 10535);
FORCEPROP 0 LASTPIN (8025 10725) $PN D7
J 0
(8035 10735);
DISPLAY 0.680851 (8035 10735);
PAINT MONO (8035 10735);
FORCEPROP 0 LASTPIN (7225 10725) $PN D1
J 2
(7215 10735);
DISPLAY 0.680851 (7215 10735);
PAINT MONO (7215 10735);
FORCEPROP 0 LASTPIN (7225 10625) $PN D2
J 2
(7215 10635);
DISPLAY 0.680851 (7215 10635);
PAINT MONO (7215 10635);
FORCEPROP 0 LASTPIN (7225 10825) $PN A2
J 2
(7215 10835);
DISPLAY 0.680851 (7215 10835);
PAINT MONO (7215 10835);
FORCEPROP 1 LAST MATERIAL IC
J 0
(7372 11280);
DISPLAY 0.723404 (7372 11280);
PAINT GREEN (7372 11280);
FORCEPROP 2 LAST VALUE MAX15090BEWI+T
J 0
(7375 11500);
DISPLAY 1.021277 (7375 11500);
FORCEPROP 0 LAST ROOM NIC_P12V_MAM_TIC_BOM1
J 0
(7375 11650);
DISPLAY 0.680851 (7375 11650);
PAINT RED (7375 11650);
FORCEPROP 2 LAST PART_TYPE SMLF
J 0
(7375 11550);
DISPLAY 1.021277 (7375 11550);
FORCEPROP 2 LAST CDS_LIB pure_quanta
J 0
(7625 10725);
DISPLAY INVISIBLE (7625 10725);
FORCEPROP 1 LAST PIN_NAMES_ROTATE True
J 0
(7625 10725);
DISPLAY 0.489362 (7625 10725);
PAINT GREEN (7625 10725);
DISPLAY INVISIBLE (7625 10725);
FORCEPROP 1 LAST CDS_LMAN_SYM_OUTLINE -250,550,250,-550
J 0
(7625 10725);
DISPLAY 0.468085 (7625 10725);
PAINT GREEN (7625 10725);
DISPLAY INVISIBLE (7625 10725);
FORCEPROP 1 LAST PATH I50
J 0
(7875 10175);
DISPLAY 0.723404 (7875 10175);
PAINT GREEN (7875 10175);
DISPLAY INVISIBLE (7875 10175);
FORCEPROP 1 LAST PART_NUMBER AL015080B00
J 0
(7372 11369);
DISPLAY 0.723404 (7372 11369);
PAINT GREEN (7372 11369);
DISPLAY INVISIBLE (7372 11369);
FORCEADD UNIVERSAL_POWER..1
(8350 9600);
FORCEPROP 3 LASTPIN (8350 9550) SIG_NAME P3V3_AUX\g
J 0
(8360 9560);
DISPLAY 0.659574 (8360 9560);
PAINT MONO (8360 9560);
DISPLAY INVISIBLE (8360 9560);
FORCEPROP 1 LAST HDL_POWER P3V3_AUX
J 1
(8350 9650);
DISPLAY 0.872340 (8350 9650);
PAINT GREEN (8350 9650);
FORCEPROP 2 LAST CDS_LIB pure_quanta_power
J 0
(8350 9600);
PAINT MONO (8350 9600);
DISPLAY INVISIBLE (8350 9600);
FORCEPROP 1 LAST PATH I52
J 0
(8400 9625);
DISPLAY 0.872340 (8400 9625);
PAINT AQUA (8400 9625);
DISPLAY INVISIBLE (8400 9625);
FORCEADD GND..1
(6250 10650);
FORCEPROP 3 LASTPIN (6250 10700) SIG_NAME GND\g
J 0
(6260 10710);
DISPLAY 0.659574 (6260 10710);
PAINT MONO (6260 10710);
DISPLAY INVISIBLE (6260 10710);
FORCEPROP 2 LAST CDS_LIB pure_quanta_power
J 0
(6250 10650);
DISPLAY INVISIBLE (6250 10650);
FORCEPROP 1 LAST SIZE 1B
J 0
(6325 10600);
DISPLAY 0.872340 (6325 10600);
PAINT GREEN (6325 10600);
DISPLAY INVISIBLE (6325 10600);
FORCEPROP 1 LAST HDL_POWER GND
J 0
(6250 10800);
DISPLAY 0.872340 (6250 10800);
PAINT GREEN (6250 10800);
DISPLAY INVISIBLE (6250 10800);
FORCEPROP 1 LAST PATH I53
J 0
(6325 10650);
DISPLAY 0.872340 (6325 10650);
PAINT AQUA (6325 10650);
DISPLAY INVISIBLE (6325 10650);
FORCEADD Q_CAP..1
R 1
(6575 10725);
FORCEPROP 1 LAST LOCATION PC2087
J 0
(6400 10775);
DISPLAY 0.638298 (6400 10775);
FORCEPROP 0 LAST $SEC 1
R 1
J 0
(6400 10825);
DISPLAY 0.680851 (6400 10825);
PAINT MONO (6400 10825);
DISPLAY INVISIBLE (6400 10825);
FORCEPROP 0 LAST CDS_SEC 1
R 1
J 0
(6400 10825);
DISPLAY 1.021277 (6400 10825);
DISPLAY INVISIBLE (6400 10825);
FORCEPROP 1 LASTPIN (6475 10725) $PN 1
R 1
J 0
(6495 10735);
DISPLAY 0.787234 (6495 10735);
PAINT MONO (6495 10735);
DISPLAY INVISIBLE (6495 10735);
FORCEPROP 1 LASTPIN (6675 10725) $PN 2
R 1
J 0
(6695 10735);
DISPLAY 0.787234 (6695 10735);
PAINT MONO (6695 10735);
DISPLAY INVISIBLE (6695 10735);
FORCEPROP 1 LAST VOLTAGE 25V
J 0
(6725 10775);
DISPLAY 0.510638 (6725 10775);
FORCEPROP 1 LAST PACK_TYPE C0402
J 0
(6400 10675);
DISPLAY 0.510638 (6400 10675);
FORCEPROP 0 LAST ROOM NIC_P12V_MAM_TIC_BOM1
J 0
(6375 10650);
DISPLAY 0.361702 (6375 10650);
PAINT RED (6375 10650);
FORCEPROP 1 LAST VALUE 1UF
J 0
(6550 10775);
DISPLAY 0.510638 (6550 10775);
FORCEPROP 1 LAST TOLERANCE 10%
R 1
J 0
(6625 10775);
DISPLAY 0.638298 (6625 10775);
DISPLAY INVISIBLE (6625 10775);
FORCEPROP 2 LAST CDS_LIB pure_quanta
J 0
(6575 10725);
DISPLAY INVISIBLE (6575 10725);
FORCEPROP 1 LAST MATERIAL X6S
R 1
J 0
(6575 10775);
DISPLAY 0.638298 (6575 10775);
DISPLAY INVISIBLE (6575 10775);
FORCEPROP 1 LAST PATH I54
R 1
J 0
(6425 10775);
DISPLAY 0.978723 (6425 10775);
PAINT WHITE (6425 10775);
DISPLAY INVISIBLE (6425 10775);
FORCEPROP 1 LAST PART_NUMBER CH5104KEB02
J 0
(6625 10675);
DISPLAY 0.510638 (6625 10675);
DISPLAY INVISIBLE (6625 10675);
FORCEADD Q_CAP..1
(6350 11025);
FORCEPROP 1 LAST LOCATION PC2085
J 0
(6400 11050);
DISPLAY 0.638298 (6400 11050);
FORCEPROP 0 LAST $SEC 1
J 0
(6400 11100);
DISPLAY 0.680851 (6400 11100);
PAINT MONO (6400 11100);
DISPLAY INVISIBLE (6400 11100);
FORCEPROP 0 LAST CDS_SEC 1
J 0
(6400 11100);
DISPLAY 1.021277 (6400 11100);
DISPLAY INVISIBLE (6400 11100);
FORCEPROP 1 LASTPIN (6350 11125) $PN 1
J 0
(6360 11105);
DISPLAY 0.787234 (6360 11105);
PAINT MONO (6360 11105);
DISPLAY INVISIBLE (6360 11105);
FORCEPROP 1 LASTPIN (6350 10925) $PN 2
J 0
(6360 10905);
DISPLAY 0.787234 (6360 10905);
PAINT MONO (6360 10905);
DISPLAY INVISIBLE (6360 10905);
FORCEPROP 1 LAST MATERIAL X6S
J 0
(6400 11000);
DISPLAY 0.510638 (6400 11000);
FORCEPROP 1 LAST VALUE 1UF
J 0
(6400 11025);
DISPLAY 0.510638 (6400 11025);
FORCEPROP 1 LAST VOLTAGE 25V
J 0
(6400 10975);
DISPLAY 0.510638 (6400 10975);
FORCEPROP 1 LAST PACK_TYPE C0402
J 0
(6400 10950);
DISPLAY 0.510638 (6400 10950);
FORCEPROP 0 LAST ROOM NIC_P12V_MAM_TIC_BOM1
J 0
(6300 10900);
DISPLAY 0.361702 (6300 10900);
PAINT RED (6300 10900);
FORCEPROP 2 LAST CDS_LIB pure_quanta
J 0
(6350 11025);
DISPLAY INVISIBLE (6350 11025);
FORCEPROP 1 LAST TOLERANCE 10%
J 0
(6400 10975);
DISPLAY 0.638298 (6400 10975);
DISPLAY INVISIBLE (6400 10975);
FORCEPROP 1 LAST PATH I55
J 0
(6400 11175);
DISPLAY 0.978723 (6400 11175);
PAINT WHITE (6400 11175);
DISPLAY INVISIBLE (6400 11175);
FORCEPROP 1 LAST PART_NUMBER CH5104KEB02
J 0
(6400 10925);
DISPLAY 0.510638 (6400 10925);
DISPLAY INVISIBLE (6400 10925);
FORCEADD Q_RES..2
(6350 11450);
FORCEPROP 1 LAST LOCATION PR3792
J 0
(6400 11525);
DISPLAY 0.638298 (6400 11525);
FORCEPROP 0 LAST $SEC 1
J 0
(6400 11575);
DISPLAY 0.680851 (6400 11575);
PAINT MONO (6400 11575);
DISPLAY INVISIBLE (6400 11575);
FORCEPROP 0 LAST CDS_SEC 1
J 0
(6400 11575);
DISPLAY 1.021277 (6400 11575);
DISPLAY INVISIBLE (6400 11575);
FORCEPROP 1 LASTPIN (6350 11550) $PN 1
J 0
(6355 11512);
DISPLAY 0.787234 (6355 11512);
PAINT MONO (6355 11512);
DISPLAY INVISIBLE (6355 11512);
FORCEPROP 1 LASTPIN (6350 11350) $PN 2
J 0
(6355 11360);
DISPLAY 0.787234 (6355 11360);
PAINT MONO (6355 11360);
DISPLAY INVISIBLE (6355 11360);
FORCEPROP 1 LAST WATTAGE 1/16W
J 0
(6400 11450);
DISPLAY 0.404255 (6400 11450);
FORCEPROP 1 LAST TOLERANCE 1%
J 0
(6400 11475);
DISPLAY 0.404255 (6400 11475);
FORCEPROP 1 LAST VALUE 10
J 0
(6400 11500);
DISPLAY 0.404255 (6400 11500);
FORCEPROP 1 LAST MATERIAL CHIP
J 0
(6400 11425);
DISPLAY 0.404255 (6400 11425);
FORCEPROP 1 LAST PACK_TYPE 0402LF
J 0
(6400 11375);
DISPLAY 0.404255 (6400 11375);
FORCEPROP 0 LAST ROOM NIC_P12V_MAM_TIC_BOM1
J 0
(6400 11350);
DISPLAY 0.446809 (6400 11350);
PAINT RED (6400 11350);
FORCEPROP 2 LAST CDS_LIB pure_quanta
J 0
(6350 11450);
DISPLAY INVISIBLE (6350 11450);
FORCEPROP 1 LAST PATH I56
J 0
(6400 11625);
DISPLAY 0.978723 (6400 11625);
PAINT WHITE (6400 11625);
DISPLAY INVISIBLE (6400 11625);
FORCEPROP 1 LAST PART_NUMBER CS01002FB07
J 0
(6400 11400);
DISPLAY 0.404255 (6400 11400);
DISPLAY INVISIBLE (6400 11400);
FORCEADD GND..1
(6250 12000);
FORCEPROP 3 LASTPIN (6250 12050) SIG_NAME GND\g
J 0
(6260 12060);
DISPLAY 0.659574 (6260 12060);
PAINT MONO (6260 12060);
DISPLAY INVISIBLE (6260 12060);
FORCEPROP 1 LAST SIZE 1B
J 0
(6325 11950);
DISPLAY 0.872340 (6325 11950);
PAINT GREEN (6325 11950);
DISPLAY INVISIBLE (6325 11950);
FORCEPROP 2 LAST CDS_LIB pure_quanta_power
J 0
(6250 12000);
DISPLAY INVISIBLE (6250 12000);
FORCEPROP 1 LAST HDL_POWER GND
J 0
(6250 12150);
DISPLAY 0.872340 (6250 12150);
PAINT GREEN (6250 12150);
DISPLAY INVISIBLE (6250 12150);
FORCEPROP 1 LAST PATH I57
J 0
(6325 12000);
DISPLAY 0.872340 (6325 12000);
PAINT AQUA (6325 12000);
DISPLAY INVISIBLE (6325 12000);
FORCEADD GND..1
(7100 11975);
FORCEPROP 3 LASTPIN (7100 12025) SIG_NAME GND\g
J 0
(7110 12035);
DISPLAY 0.659574 (7110 12035);
PAINT MONO (7110 12035);
DISPLAY INVISIBLE (7110 12035);
FORCEPROP 2 LAST CDS_LIB pure_quanta_power
J 0
(7100 11975);
DISPLAY INVISIBLE (7100 11975);
FORCEPROP 1 LAST SIZE 1B
J 0
(7175 11925);
DISPLAY 0.872340 (7175 11925);
PAINT GREEN (7175 11925);
DISPLAY INVISIBLE (7175 11925);
FORCEPROP 1 LAST HDL_POWER GND
J 0
(7100 12125);
DISPLAY 0.872340 (7100 12125);
PAINT GREEN (7100 12125);
DISPLAY INVISIBLE (7100 12125);
FORCEPROP 1 LAST PATH I58
J 0
(7175 11975);
DISPLAY 0.872340 (7175 11975);
PAINT AQUA (7175 11975);
DISPLAY INVISIBLE (7175 11975);
FORCEADD Q_RES..2
(4225 12475);
FORCEPROP 1 LAST LOCATION R4070
J 0
(4260 12642);
DISPLAY 0.638298 (4260 12642);
FORCEPROP 0 LAST $SEC 1
J 0
(4275 12675);
DISPLAY 0.680851 (4275 12675);
PAINT MONO (4275 12675);
DISPLAY INVISIBLE (4275 12675);
FORCEPROP 0 LAST CDS_SEC 1
J 0
(4275 12675);
DISPLAY 1.021277 (4275 12675);
DISPLAY INVISIBLE (4275 12675);
FORCEPROP 1 LASTPIN (4225 12575) $PN 1
J 0
(4230 12537);
DISPLAY 0.787234 (4230 12537);
PAINT MONO (4230 12537);
FORCEPROP 1 LASTPIN (4225 12375) $PN 2
J 0
(4230 12385);
DISPLAY 0.787234 (4230 12385);
PAINT MONO (4230 12385);
FORCEPROP 0 LAST ROOM NIC_P3V3_BOM1
J 0
(4275 12725);
DISPLAY 0.680851 (4275 12725);
PAINT RED (4275 12725);
FORCEPROP 1 LAST WATTAGE 1/16W
J 0
(4255 12492);
DISPLAY 0.638298 (4255 12492);
FORCEPROP 1 LAST VALUE 10K
J 0
(4260 12592);
DISPLAY 0.638298 (4260 12592);
FORCEPROP 1 LAST PACK_TYPE 0402LF
J 0
(4255 12342);
DISPLAY 0.638298 (4255 12342);
FORCEPROP 1 LAST TOLERANCE 1%
J 0
(4260 12542);
DISPLAY 0.638298 (4260 12542);
FORCEPROP 1 LAST MATERIAL CHIP
J 0
(4255 12442);
DISPLAY 0.638298 (4255 12442);
FORCEPROP 2 LAST CDS_LIB pure_quanta
J 0
(4225 12475);
DISPLAY INVISIBLE (4225 12475);
FORCEPROP 1 LAST PATH I59
J 0
(4275 12650);
DISPLAY 0.978723 (4275 12650);
PAINT WHITE (4275 12650);
DISPLAY INVISIBLE (4275 12650);
FORCEPROP 1 LAST PART_NUMBER CS31002FB08
J 0
(4255 12392);
DISPLAY 0.638298 (4255 12392);
DISPLAY INVISIBLE (4255 12392);
FORCEADD UNIVERSAL_POWER..1
(4225 12725);
FORCEPROP 3 LASTPIN (4225 12675) SIG_NAME P12V_AUX\g
J 0
(4235 12685);
DISPLAY 0.659574 (4235 12685);
PAINT MONO (4235 12685);
DISPLAY INVISIBLE (4235 12685);
FORCEPROP 1 LAST HDL_POWER P12V_AUX
J 1
(4225 12775);
DISPLAY 0.872340 (4225 12775);
PAINT GREEN (4225 12775);
FORCEPROP 2 LAST CDS_LIB pure_quanta_power
J 0
(4225 12725);
DISPLAY INVISIBLE (4225 12725);
FORCEPROP 1 LAST PATH I60
J 0
(4275 12750);
DISPLAY 0.872340 (4275 12750);
PAINT AQUA (4275 12750);
DISPLAY INVISIBLE (4275 12750);
FORCEADD Q_RES..1
(5650 12875);
FORCEPROP 1 LAST LOCATION R3785
J 0
(5600 12925);
DISPLAY 0.978723 (5600 12925);
FORCEPROP 0 LAST $SEC 1
J 0
(5600 12975);
DISPLAY 0.680851 (5600 12975);
PAINT MONO (5600 12975);
DISPLAY INVISIBLE (5600 12975);
FORCEPROP 0 LAST CDS_SEC 1
J 0
(5600 12975);
DISPLAY 1.021277 (5600 12975);
DISPLAY INVISIBLE (5600 12975);
FORCEPROP 1 LASTPIN (5550 12875) $PN 1
J 0
(5562 12887);
DISPLAY 0.787234 (5562 12887);
PAINT MONO (5562 12887);
DISPLAY INVISIBLE (5562 12887);
FORCEPROP 1 LASTPIN (5750 12875) $PN 2
J 0
(5712 12887);
DISPLAY 0.787234 (5712 12887);
PAINT MONO (5712 12887);
DISPLAY INVISIBLE (5712 12887);
FORCEPROP 1 LAST VALUE 0
J 2
(5775 12875);
DISPLAY 0.510638 (5775 12875);
FORCEPROP 1 LAST WATTAGE 1/16W
J 2
(5825 12800);
DISPLAY 0.510638 (5825 12800);
FORCEPROP 1 LAST TOLERANCE 5%
J 0
(5800 12875);
DISPLAY 0.510638 (5800 12875);
FORCEPROP 1 LAST MATERIAL CHIP
J 0
(5575 12800);
DISPLAY 0.510638 (5575 12800);
FORCEPROP 0 LAST ROOM NIC_P3V3_BOM1
J 0
(5600 13025);
DISPLAY 0.680851 (5600 13025);
PAINT RED (5600 13025);
FORCEPROP 1 LAST PACK_TYPE 0402LF
J 0
(5875 12875);
DISPLAY 0.510638 (5875 12875);
FORCEPROP 2 LAST CDS_LIB pure_quanta
J 0
(5650 12875);
DISPLAY INVISIBLE (5650 12875);
FORCEPROP 1 LAST PATH I61
J 0
(5600 13025);
DISPLAY 0.978723 (5600 13025);
PAINT WHITE (5600 13025);
DISPLAY INVISIBLE (5600 13025);
FORCEPROP 1 LAST PART_NUMBER CS00002JB13
J 0
(5575 12825);
DISPLAY 0.510638 (5575 12825);
DISPLAY INVISIBLE (5575 12825);
FORCEADD Q_CAP..1
(5900 13500);
FORCEPROP 1 LAST LOCATION PC5328
J 0
(5950 13575);
DISPLAY 0.638298 (5950 13575);
FORCEPROP 0 LAST $SEC 1
J 0
(5955 13642);
DISPLAY INVISIBLE (5955 13642);
FORCEPROP 0 LAST CDS_SEC 1
J 0
(5955 13642);
DISPLAY INVISIBLE (5955 13642);
FORCEPROP 1 LASTPIN (5900 13600) $PN 1
J 0
(5910 13580);
DISPLAY 0.787234 (5910 13580);
PAINT MONO (5910 13580);
DISPLAY INVISIBLE (5910 13580);
FORCEPROP 1 LASTPIN (5900 13400) $PN 2
J 0
(5910 13380);
DISPLAY 0.787234 (5910 13380);
PAINT MONO (5910 13380);
DISPLAY INVISIBLE (5910 13380);
FORCEPROP 1 LAST PACK_TYPE C0402
J 0
(5950 13475);
DISPLAY 0.510638 (5950 13475);
FORCEPROP 1 LAST MATERIAL X6S
J 0
(5950 13500);
DISPLAY 0.510638 (5950 13500);
FORCEPROP 1 LAST VOLTAGE 25V
J 0
(5950 13525);
DISPLAY 0.510638 (5950 13525);
FORCEPROP 1 LAST VALUE 1UF
J 0
(5950 13550);
DISPLAY 0.510638 (5950 13550);
FORCEPROP 2 LAST CDS_LIB pure_quanta
J 0
(5900 13500);
DISPLAY INVISIBLE (5900 13500);
FORCEPROP 1 LAST TOLERANCE 10%
J 0
(5950 13450);
DISPLAY 0.638298 (5950 13450);
DISPLAY INVISIBLE (5950 13450);
FORCEPROP 1 LAST PATH I62
J 0
(5950 13650);
DISPLAY 0.978723 (5950 13650);
PAINT WHITE (5950 13650);
DISPLAY INVISIBLE (5950 13650);
FORCEPROP 1 LAST PART_NUMBER CH5104KEB02
J 0
(5950 13450);
DISPLAY 0.510638 (5950 13450);
DISPLAY INVISIBLE (5950 13450);
FORCEADD UNIVERSAL_POWER..1
(5900 13850);
FORCEPROP 3 LASTPIN (5900 13800) SIG_NAME P3V3_AUX\g
J 0
(5910 13810);
DISPLAY 0.659574 (5910 13810);
PAINT MONO (5910 13810);
DISPLAY INVISIBLE (5910 13810);
FORCEPROP 1 LAST HDL_POWER P3V3_AUX
J 1
(5900 13900);
DISPLAY 0.872340 (5900 13900);
PAINT GREEN (5900 13900);
FORCEPROP 2 LAST CDS_LIB pure_quanta_power
J 0
(5900 13850);
DISPLAY INVISIBLE (5900 13850);
FORCEPROP 1 LAST PATH I63
J 0
(5950 13875);
DISPLAY 0.872340 (5950 13875);
PAINT AQUA (5950 13875);
DISPLAY INVISIBLE (5950 13875);
FORCEADD Q_RES..2
(6250 12525);
FORCEPROP 1 LAST LOCATION PR3790
J 0
(6300 12600);
DISPLAY 0.638298 (6300 12600);
FORCEPROP 0 LAST $SEC 1
J 0
(6300 12650);
DISPLAY 0.680851 (6300 12650);
PAINT MONO (6300 12650);
DISPLAY INVISIBLE (6300 12650);
FORCEPROP 0 LAST CDS_SEC 1
J 0
(6300 12650);
DISPLAY 1.021277 (6300 12650);
DISPLAY INVISIBLE (6300 12650);
FORCEPROP 1 LASTPIN (6250 12625) $PN 1
J 0
(6255 12587);
DISPLAY 0.787234 (6255 12587);
PAINT MONO (6255 12587);
DISPLAY INVISIBLE (6255 12587);
FORCEPROP 1 LASTPIN (6250 12425) $PN 2
J 0
(6255 12435);
DISPLAY 0.787234 (6255 12435);
PAINT MONO (6255 12435);
DISPLAY INVISIBLE (6255 12435);
FORCEPROP 1 LAST WATTAGE 1/16W
J 0
(6300 12525);
DISPLAY 0.404255 (6300 12525);
FORCEPROP 1 LAST TOLERANCE 1%
J 0
(6300 12550);
DISPLAY 0.404255 (6300 12550);
FORCEPROP 1 LAST VALUE 7.15K
J 0
(6300 12575);
DISPLAY 0.404255 (6300 12575);
FORCEPROP 1 LAST MATERIAL CHIP
J 0
(6300 12500);
DISPLAY 0.404255 (6300 12500);
FORCEPROP 0 LAST ROOM NIC_P3V3_BOM1
J 0
(6275 12425);
DISPLAY 0.446809 (6275 12425);
PAINT RED (6275 12425);
FORCEPROP 1 LAST PACK_TYPE 0402LF
J 0
(6300 12450);
DISPLAY 0.404255 (6300 12450);
FORCEPROP 2 LAST CDS_LIB pure_quanta
J 0
(6250 12525);
DISPLAY INVISIBLE (6250 12525);
FORCEPROP 1 LAST PATH I64
J 0
(6300 12700);
DISPLAY 0.978723 (6300 12700);
PAINT WHITE (6300 12700);
DISPLAY INVISIBLE (6300 12700);
FORCEPROP 1 LAST PART_NUMBER CS27152FB03
J 0
(6300 12475);
DISPLAY 0.404255 (6300 12475);
DISPLAY INVISIBLE (6300 12475);
FORCEADD GND..1
(6575 12700);
FORCEPROP 3 LASTPIN (6575 12750) SIG_NAME GND\g
J 0
(6585 12760);
DISPLAY 0.659574 (6585 12760);
PAINT MONO (6585 12760);
DISPLAY INVISIBLE (6585 12760);
FORCEPROP 2 LAST CDS_LIB pure_quanta_power
J 0
(6575 12700);
DISPLAY INVISIBLE (6575 12700);
FORCEPROP 1 LAST SIZE 1B
J 0
(6650 12650);
DISPLAY 0.872340 (6650 12650);
PAINT GREEN (6650 12650);
DISPLAY INVISIBLE (6650 12650);
FORCEPROP 1 LAST HDL_POWER GND
J 0
(6575 12850);
DISPLAY 0.872340 (6575 12850);
PAINT GREEN (6575 12850);
DISPLAY INVISIBLE (6575 12850);
FORCEPROP 1 LAST PATH I65
J 0
(6650 12700);
DISPLAY 0.872340 (6650 12700);
PAINT AQUA (6650 12700);
DISPLAY INVISIBLE (6650 12700);
FORCEADD Q_RES..2
(6250 13250);
FORCEPROP 1 LAST LOCATION PR3789
J 0
(6300 13325);
DISPLAY 0.638298 (6300 13325);
FORCEPROP 0 LAST $SEC 1
J 0
(6300 13375);
DISPLAY 0.680851 (6300 13375);
PAINT MONO (6300 13375);
DISPLAY INVISIBLE (6300 13375);
FORCEPROP 0 LAST CDS_SEC 1
J 0
(6300 13375);
DISPLAY 1.021277 (6300 13375);
DISPLAY INVISIBLE (6300 13375);
FORCEPROP 1 LASTPIN (6250 13350) $PN 1
J 0
(6255 13312);
DISPLAY 0.787234 (6255 13312);
PAINT MONO (6255 13312);
DISPLAY INVISIBLE (6255 13312);
FORCEPROP 1 LASTPIN (6250 13150) $PN 2
J 0
(6255 13160);
DISPLAY 0.787234 (6255 13160);
PAINT MONO (6255 13160);
DISPLAY INVISIBLE (6255 13160);
FORCEPROP 0 LAST ROOM NIC_P3V3_BOM1
J 0
(6300 13375);
DISPLAY 0.446809 (6300 13375);
PAINT RED (6300 13375);
FORCEPROP 1 LAST PACK_TYPE 0402LF
J 0
(6300 13175);
DISPLAY 0.404255 (6300 13175);
FORCEPROP 1 LAST VALUE 25.5K
J 0
(6300 13300);
DISPLAY 0.404255 (6300 13300);
FORCEPROP 1 LAST MATERIAL CHIP
J 0
(6300 13225);
DISPLAY 0.404255 (6300 13225);
FORCEPROP 1 LAST WATTAGE 1/16W
J 0
(6300 13250);
DISPLAY 0.404255 (6300 13250);
FORCEPROP 1 LAST TOLERANCE 1%
J 0
(6300 13275);
DISPLAY 0.404255 (6300 13275);
FORCEPROP 2 LAST CDS_LIB pure_quanta
J 0
(6250 13250);
DISPLAY INVISIBLE (6250 13250);
FORCEPROP 1 LAST PATH I66
J 0
(6300 13425);
DISPLAY 0.978723 (6300 13425);
PAINT WHITE (6300 13425);
DISPLAY INVISIBLE (6300 13425);
FORCEPROP 1 LAST PART_NUMBER CS32552FB06
J 0
(6300 13200);
DISPLAY 0.404255 (6300 13200);
DISPLAY INVISIBLE (6300 13200);
FORCEADD Q_CAP..1
R 1
(6800 12775);
FORCEPROP 1 LAST LOCATION PC2093
J 0
(6600 12800);
DISPLAY 0.638298 (6600 12800);
FORCEPROP 0 LAST $SEC 1
R 1
J 0
(6625 12875);
DISPLAY 0.680851 (6625 12875);
PAINT MONO (6625 12875);
DISPLAY INVISIBLE (6625 12875);
FORCEPROP 0 LAST CDS_SEC 1
R 1
J 0
(6625 12875);
DISPLAY 1.021277 (6625 12875);
DISPLAY INVISIBLE (6625 12875);
FORCEPROP 1 LASTPIN (6700 12775) $PN 1
R 1
J 0
(6720 12785);
DISPLAY 0.787234 (6720 12785);
PAINT MONO (6720 12785);
DISPLAY INVISIBLE (6720 12785);
FORCEPROP 1 LASTPIN (6900 12775) $PN 2
R 1
J 0
(6920 12785);
DISPLAY 0.787234 (6920 12785);
PAINT MONO (6920 12785);
DISPLAY INVISIBLE (6920 12785);
FORCEPROP 1 LAST PACK_TYPE C0402
J 0
(6625 12725);
DISPLAY 0.510638 (6625 12725);
FORCEPROP 0 LAST ROOM NIC_P3V3_BOM1
J 0
(6650 12700);
DISPLAY 0.446809 (6650 12700);
PAINT RED (6650 12700);
FORCEPROP 1 LAST VALUE 1UF
J 0
(6775 12825);
DISPLAY 0.510638 (6775 12825);
FORCEPROP 1 LAST VOLTAGE 25V
J 0
(6925 12825);
DISPLAY 0.510638 (6925 12825);
FORCEPROP 1 LAST MATERIAL X6S
R 1
J 0
(6800 12825);
DISPLAY 0.638298 (6800 12825);
DISPLAY INVISIBLE (6800 12825);
FORCEPROP 2 LAST CDS_LIB pure_quanta
J 0
(6800 12775);
DISPLAY INVISIBLE (6800 12775);
FORCEPROP 1 LAST TOLERANCE 10%
R 1
J 0
(6850 12825);
DISPLAY 0.638298 (6850 12825);
DISPLAY INVISIBLE (6850 12825);
FORCEPROP 1 LAST PATH I67
R 1
J 0
(6650 12825);
DISPLAY 0.978723 (6650 12825);
PAINT WHITE (6650 12825);
DISPLAY INVISIBLE (6650 12825);
FORCEPROP 1 LAST PART_NUMBER CH5104KEB02
J 0
(6850 12725);
DISPLAY 0.510638 (6850 12725);
DISPLAY INVISIBLE (6850 12725);
FORCEADD Q_RES..2
(6575 13500);
FORCEPROP 1 LAST LOCATION PR3798
J 0
(6625 13575);
DISPLAY 0.638298 (6625 13575);
FORCEPROP 0 LAST $SEC 1
J 0
(6625 13625);
DISPLAY 0.680851 (6625 13625);
PAINT MONO (6625 13625);
DISPLAY INVISIBLE (6625 13625);
FORCEPROP 0 LAST CDS_SEC 1
J 0
(6625 13625);
DISPLAY 1.021277 (6625 13625);
DISPLAY INVISIBLE (6625 13625);
FORCEPROP 1 LASTPIN (6575 13600) $PN 1
J 0
(6580 13562);
DISPLAY 0.787234 (6580 13562);
PAINT MONO (6580 13562);
DISPLAY INVISIBLE (6580 13562);
FORCEPROP 1 LASTPIN (6575 13400) $PN 2
J 0
(6580 13410);
DISPLAY 0.787234 (6580 13410);
PAINT MONO (6580 13410);
DISPLAY INVISIBLE (6580 13410);
FORCEPROP 1 LAST WATTAGE 1/16W
J 0
(6625 13500);
DISPLAY 0.404255 (6625 13500);
FORCEPROP 1 LAST PACK_TYPE 0402LF
J 0
(6625 13425);
DISPLAY 0.404255 (6625 13425);
FORCEPROP 1 LAST MATERIAL CHIP
J 0
(6625 13475);
DISPLAY 0.404255 (6625 13475);
FORCEPROP 1 LAST TOLERANCE 1%
J 0
(6625 13525);
DISPLAY 0.404255 (6625 13525);
FORCEPROP 1 LAST VALUE 10
J 0
(6625 13550);
DISPLAY 0.404255 (6625 13550);
FORCEPROP 0 LAST ROOM NIC_P3V3_BOM1
J 0
(6625 13625);
DISPLAY 0.553191 (6625 13625);
PAINT RED (6625 13625);
FORCEPROP 2 LAST CDS_LIB pure_quanta
J 0
(6575 13500);
DISPLAY INVISIBLE (6575 13500);
FORCEPROP 1 LAST PATH I68
J 0
(6625 13675);
DISPLAY 0.978723 (6625 13675);
PAINT WHITE (6625 13675);
DISPLAY INVISIBLE (6625 13675);
FORCEPROP 1 LAST PART_NUMBER CS01002FB07
J 0
(6625 13450);
DISPLAY 0.404255 (6625 13450);
DISPLAY INVISIBLE (6625 13450);
FORCEADD OFFPAGE..2
(8475 8900);
FORCEPROP 2 LAST $XR0 81 
J 0
(8664 8900);
DISPLAY 0.638298 (8664 8900);
PAINT MONO (8664 8900);
FORCEPROP 2 LAST CDS_LIB standard
J 0
(8475 8900);
PAINT MONO (8475 8900);
DISPLAY INVISIBLE (8475 8900);
FORCEPROP 1 LAST OFFPAGE TRUE
J 0
(8800 8775);
DISPLAY 0.872340 (8800 8775);
DISPLAY INVISIBLE (8800 8775);
FORCEPROP 1 LAST COMMENT_BODY TRUE
J 0
(8430 8805);
DISPLAY 0.872340 (8430 8805);
PAINT GREEN (8430 8805);
DISPLAY INVISIBLE (8430 8805);
FORCEPROP 2 LAST PATH I69
J 0
(8675 8950);
DISPLAY 0.680851 (8675 8950);
DISPLAY INVISIBLE (8675 8950);
FORCEADD OFFPAGE..1
(3725 8600);
FORCEPROP 2 LAST $XR0 131 
J 0
(3443 8600);
DISPLAY 0.638298 (3443 8600);
PAINT MONO (3443 8600);
FORCEPROP 2 LAST $XR1 143 
J 0
(3323 8600);
DISPLAY 0.638298 (3323 8600);
PAINT MONO (3323 8600);
FORCEPROP 2 LAST CDS_LIB standard
J 0
(3725 8600);
PAINT MONO (3725 8600);
DISPLAY INVISIBLE (3725 8600);
FORCEPROP 1 LAST OFFPAGE TRUE
J 0
(4050 8475);
DISPLAY 0.872340 (4050 8475);
PAINT GREEN (4050 8475);
DISPLAY INVISIBLE (4050 8475);
FORCEPROP 1 LAST COMMENT_BODY TRUE
J 0
(3850 8500);
DISPLAY 0.872340 (3850 8500);
PAINT GREEN (3850 8500);
DISPLAY INVISIBLE (3850 8500);
FORCEPROP 2 LAST PATH I7
J 0
(3475 8650);
DISPLAY 0.680851 (3475 8650);
DISPLAY INVISIBLE (3475 8650);
FORCEADD Q_RES..2
(8350 9325);
FORCEPROP 1 LAST LOCATION R1150
J 0
(8395 9450);
DISPLAY 0.978723 (8395 9450);
FORCEPROP 2 LAST $SEC 1
J 0
(8400 9550);
DISPLAY 0.680851 (8400 9550);
PAINT MONO (8400 9550);
DISPLAY INVISIBLE (8400 9550);
FORCEPROP 2 LAST CDS_SEC 1
J 0
(8400 9550);
DISPLAY 1.021277 (8400 9550);
DISPLAY INVISIBLE (8400 9550);
FORCEPROP 1 LASTPIN (8350 9425) $PN 1
J 0
(8355 9387);
DISPLAY 0.787234 (8355 9387);
FORCEPROP 1 LASTPIN (8350 9225) $PN 2
J 0
(8355 9235);
DISPLAY 0.787234 (8355 9235);
FORCEPROP 1 LAST WATTAGE 1/16W
J 0
(8390 9300);
DISPLAY 0.510638 (8390 9300);
FORCEPROP 1 LAST TOLERANCE 1%
J 0
(8395 9350);
DISPLAY 0.510638 (8395 9350);
FORCEPROP 1 LAST MATERIAL CHIP
J 0
(8390 9250);
DISPLAY 0.510638 (8390 9250);
FORCEPROP 1 LAST VALUE 10K
J 0
(8395 9400);
DISPLAY 0.510638 (8395 9400);
FORCEPROP 1 LAST PACK_TYPE 0402LF
J 0
(8390 9200);
DISPLAY 0.510638 (8390 9200);
FORCEPROP 2 LAST CDS_LIB pure_quanta
J 0
(8350 9325);
PAINT MONO (8350 9325);
DISPLAY INVISIBLE (8350 9325);
FORCEPROP 1 LAST PATH I71
J 0
(8400 9500);
DISPLAY 0.978723 (8400 9500);
PAINT WHITE (8400 9500);
DISPLAY INVISIBLE (8400 9500);
FORCEPROP 1 LAST PART_NUMBER CS31002FB08
J 0
(8390 9150);
DISPLAY 0.510638 (8390 9150);
DISPLAY INVISIBLE (8390 9150);
FORCEADD GND..1
(8350 10050);
FORCEPROP 3 LASTPIN (8350 10100) SIG_NAME GND\g
J 0
(8360 10110);
DISPLAY 0.659574 (8360 10110);
PAINT MONO (8360 10110);
DISPLAY INVISIBLE (8360 10110);
FORCEPROP 1 LAST SIZE 1B
J 0
(8425 10000);
DISPLAY 0.872340 (8425 10000);
PAINT GREEN (8425 10000);
DISPLAY INVISIBLE (8425 10000);
FORCEPROP 2 LAST CDS_LIB pure_quanta_power
J 0
(8350 10050);
DISPLAY INVISIBLE (8350 10050);
FORCEPROP 1 LAST HDL_POWER GND
J 0
(8350 10200);
DISPLAY 0.872340 (8350 10200);
PAINT GREEN (8350 10200);
DISPLAY INVISIBLE (8350 10200);
FORCEPROP 1 LAST PATH I72
J 0
(8425 10050);
DISPLAY 0.872340 (8425 10050);
PAINT AQUA (8425 10050);
DISPLAY INVISIBLE (8425 10050);
FORCEADD Q_RES..2
(8475 10325);
FORCEPROP 1 LAST LOCATION PR3781
J 0
(8520 10450);
DISPLAY 0.638298 (8520 10450);
FORCEPROP 0 LAST $SEC 1
J 0
(8525 10500);
DISPLAY 0.680851 (8525 10500);
PAINT MONO (8525 10500);
DISPLAY INVISIBLE (8525 10500);
FORCEPROP 0 LAST CDS_SEC 1
J 0
(8525 10500);
DISPLAY 1.021277 (8525 10500);
DISPLAY INVISIBLE (8525 10500);
FORCEPROP 1 LASTPIN (8475 10425) $PN 1
J 0
(8480 10387);
DISPLAY 0.787234 (8480 10387);
PAINT MONO (8480 10387);
FORCEPROP 1 LASTPIN (8475 10225) $PN 2
J 0
(8480 10235);
DISPLAY 0.787234 (8480 10235);
PAINT MONO (8480 10235);
FORCEPROP 1 LAST MATERIAL CHIP
J 0
(8515 10250);
DISPLAY 0.638298 (8515 10250);
FORCEPROP 0 LAST ROOM NIC_P12V_MAM_TIC_BOM1
J 0
(8500 10100);
DISPLAY 0.446809 (8500 10100);
PAINT RED (8500 10100);
FORCEPROP 1 LAST VALUE 845
J 0
(8520 10400);
DISPLAY 0.638298 (8520 10400);
FORCEPROP 1 LAST WATTAGE 1/16W
J 0
(8515 10300);
DISPLAY 0.638298 (8515 10300);
FORCEPROP 1 LAST TOLERANCE 1%
J 0
(8520 10350);
DISPLAY 0.638298 (8520 10350);
FORCEPROP 1 LAST PACK_TYPE 0402LF
J 0
(8515 10150);
DISPLAY 0.638298 (8515 10150);
FORCEPROP 2 LAST CDS_LIB pure_quanta
J 0
(8475 10325);
DISPLAY INVISIBLE (8475 10325);
FORCEPROP 1 LAST PATH I73
J 0
(8525 10500);
DISPLAY 0.978723 (8525 10500);
PAINT WHITE (8525 10500);
DISPLAY INVISIBLE (8525 10500);
FORCEPROP 1 LAST PART_NUMBER CS18452FB01
J 0
(8515 10200);
DISPLAY 0.638298 (8515 10200);
DISPLAY INVISIBLE (8515 10200);
FORCEADD Q_CAP..1
(8400 11050);
FORCEPROP 1 LAST LOCATION PC2088
J 0
(8450 11150);
DISPLAY 0.510638 (8450 11150);
FORCEPROP 0 LAST $SEC 1
J 0
(8450 11200);
DISPLAY 0.680851 (8450 11200);
PAINT MONO (8450 11200);
DISPLAY INVISIBLE (8450 11200);
FORCEPROP 0 LAST CDS_SEC 1
J 0
(8450 11200);
DISPLAY 1.021277 (8450 11200);
DISPLAY INVISIBLE (8450 11200);
FORCEPROP 1 LASTPIN (8400 11150) $PN 1
J 0
(8410 11130);
DISPLAY 0.787234 (8410 11130);
PAINT MONO (8410 11130);
DISPLAY INVISIBLE (8410 11130);
FORCEPROP 1 LASTPIN (8400 10950) $PN 2
J 0
(8410 10930);
DISPLAY 0.787234 (8410 10930);
PAINT MONO (8410 10930);
DISPLAY INVISIBLE (8410 10930);
FORCEPROP 1 LAST VOLTAGE 50V
J 0
(8455 11042);
DISPLAY 0.510638 (8455 11042);
FORCEPROP 1 LAST VALUE 0.01UF
J 0
(8450 11100);
DISPLAY 0.510638 (8450 11100);
FORCEPROP 1 LAST MATERIAL EMPTY
J 0
(8450 10900);
DISPLAY 0.638298 (8450 10900);
PAINT RED (8450 10900);
FORCEPROP 0 LAST ROOM NIC_P12V_MAM_TIC_BOM1
J 0
(8350 10875);
DISPLAY 0.361702 (8350 10875);
PAINT RED (8350 10875);
FORCEPROP 1 LAST PACK_TYPE C0402
J 0
(8455 10992);
DISPLAY 0.510638 (8455 10992);
FORCEPROP 2 LAST CDS_LIB pure_quanta
J 0
(8400 11050);
DISPLAY INVISIBLE (8400 11050);
FORCEPROP 1 LAST TOLERANCE 10%
J 0
(8450 11000);
DISPLAY 0.638298 (8450 11000);
DISPLAY INVISIBLE (8450 11000);
FORCEPROP 1 LAST PATH I74
J 0
(8450 11200);
DISPLAY 0.978723 (8450 11200);
PAINT WHITE (8450 11200);
DISPLAY INVISIBLE (8450 11200);
FORCEPROP 1 LAST PART_NUMBER CH31006KB18
J 0
(8455 10942);
DISPLAY 0.510638 (8455 10942);
DISPLAY INVISIBLE (8455 10942);
FORCEADD Q_RES..1
(9125 10725);
FORCEPROP 1 LAST LOCATION R3144
J 0
(8775 10725);
DISPLAY 0.638298 (8775 10725);
FORCEPROP 0 LAST $SEC 1
J 0
(9100 10800);
DISPLAY 0.680851 (9100 10800);
PAINT MONO (9100 10800);
DISPLAY INVISIBLE (9100 10800);
FORCEPROP 0 LAST CDS_SEC 1
J 0
(9100 10800);
DISPLAY 1.021277 (9100 10800);
DISPLAY INVISIBLE (9100 10800);
FORCEPROP 1 LASTPIN (9025 10725) $PN 1
J 0
(9037 10737);
DISPLAY 0.787234 (9037 10737);
PAINT MONO (9037 10737);
DISPLAY INVISIBLE (9037 10737);
FORCEPROP 1 LASTPIN (9225 10725) $PN 2
J 0
(9187 10737);
DISPLAY 0.787234 (9187 10737);
PAINT MONO (9187 10737);
DISPLAY INVISIBLE (9187 10737);
FORCEPROP 1 LAST VALUE 0
J 2
(9275 10725);
DISPLAY 0.595745 (9275 10725);
FORCEPROP 1 LAST TOLERANCE 5%
J 0
(9300 10725);
DISPLAY 0.595745 (9300 10725);
FORCEPROP 1 LAST MATERIAL CHIP
J 0
(8900 10725);
DISPLAY 0.595745 (8900 10725);
FORCEPROP 0 LAST ROOM NIC_P12V_MAM_TIC_BOM1
J 0
(8875 10650);
DISPLAY 0.446809 (8875 10650);
PAINT RED (8875 10650);
FORCEPROP 1 LAST PACK_TYPE 0402LF
J 0
(9275 10675);
DISPLAY 0.595745 (9275 10675);
FORCEPROP 1 LAST WATTAGE 1/16W
J 2
(8925 10675);
DISPLAY 0.595745 (8925 10675);
FORCEPROP 2 LAST CDS_LIB pure_quanta
J 0
(9125 10725);
DISPLAY INVISIBLE (9125 10725);
FORCEPROP 1 LAST PATH I75
J 0
(9075 10875);
DISPLAY 0.978723 (9075 10875);
PAINT WHITE (9075 10875);
DISPLAY INVISIBLE (9075 10875);
FORCEPROP 1 LAST PART_NUMBER CS00002JB13
J 0
(8950 10675);
DISPLAY 0.595745 (8950 10675);
DISPLAY INVISIBLE (8950 10675);
FORCEADD Q_RES..2
(8725 11050);
FORCEPROP 1 LAST LOCATION PR4524
J 0
(8770 11175);
DISPLAY 0.787234 (8770 11175);
FORCEPROP 0 LAST $SEC 1
J 0
(8775 11225);
DISPLAY 0.680851 (8775 11225);
PAINT MONO (8775 11225);
DISPLAY INVISIBLE (8775 11225);
FORCEPROP 0 LAST CDS_SEC 1
J 0
(8775 11225);
DISPLAY 1.021277 (8775 11225);
DISPLAY INVISIBLE (8775 11225);
FORCEPROP 1 LASTPIN (8725 11150) $PN 1
J 0
(8730 11112);
DISPLAY 0.787234 (8730 11112);
PAINT MONO (8730 11112);
FORCEPROP 1 LASTPIN (8725 10950) $PN 2
J 0
(8730 10960);
DISPLAY 0.787234 (8730 10960);
PAINT MONO (8730 10960);
FORCEPROP 1 LAST TOLERANCE 1%
J 0
(8775 11125);
DISPLAY 0.510638 (8775 11125);
FORCEPROP 1 LAST MATERIAL CHIP
J 0
(8775 11075);
DISPLAY 0.510638 (8775 11075);
FORCEPROP 1 LAST WATTAGE 1/16W
J 0
(8775 11100);
DISPLAY 0.510638 (8775 11100);
FORCEPROP 1 LAST VALUE 10M
J 0
(8775 11150);
DISPLAY 0.510638 (8775 11150);
FORCEPROP 0 LAST ROOM NIC_P12V_MAM_TIC_BOM1
J 0
(8775 11225);
DISPLAY 0.446809 (8775 11225);
PAINT RED (8775 11225);
FORCEPROP 1 LAST PACK_TYPE 0402LF
J 0
(8775 11025);
DISPLAY 0.510638 (8775 11025);
FORCEPROP 2 LAST CDS_LIB pure_quanta
J 0
(8725 11050);
DISPLAY INVISIBLE (8725 11050);
FORCEPROP 1 LAST PATH I76
J 0
(8775 11225);
DISPLAY 0.978723 (8775 11225);
PAINT WHITE (8775 11225);
DISPLAY INVISIBLE (8775 11225);
FORCEPROP 1 LAST PART_NUMBER CS61002FB02
J 0
(8775 11050);
DISPLAY 0.510638 (8775 11050);
DISPLAY INVISIBLE (8775 11050);
FORCEADD Q_CAP..1
R 1
(9075 10825);
FORCEPROP 1 LAST LOCATION PC4056
J 0
(8850 10825);
DISPLAY 0.510638 (8850 10825);
FORCEPROP 0 LAST $SEC 1
R 1
J 0
(9175 10950);
DISPLAY 0.680851 (9175 10950);
PAINT MONO (9175 10950);
DISPLAY INVISIBLE (9175 10950);
FORCEPROP 0 LAST CDS_SEC 1
R 1
J 0
(9175 10950);
DISPLAY 1.021277 (9175 10950);
DISPLAY INVISIBLE (9175 10950);
FORCEPROP 1 LASTPIN (8975 10825) $PN 1
R 1
J 0
(8995 10835);
DISPLAY 0.787234 (8995 10835);
PAINT MONO (8995 10835);
DISPLAY INVISIBLE (8995 10835);
FORCEPROP 1 LASTPIN (9175 10825) $PN 2
R 1
J 0
(9195 10835);
DISPLAY 0.787234 (9195 10835);
PAINT MONO (9195 10835);
DISPLAY INVISIBLE (9195 10835);
FORCEPROP 1 LAST VOLTAGE 50V
J 0
(9175 10875);
DISPLAY 0.510638 (9175 10875);
FORCEPROP 1 LAST PACK_TYPE C0402
J 0
(8850 10800);
DISPLAY 0.510638 (8850 10800);
FORCEPROP 1 LAST VALUE 3900PF
J 0
(8975 10875);
DISPLAY 0.510638 (8975 10875);
FORCEPROP 0 LAST ROOM NIC_P12V_MAM_TIC_BOM1
J 0
(8850 10900);
DISPLAY 0.446809 (8850 10900);
PAINT RED (8850 10900);
FORCEPROP 2 LAST CDS_LIB pure_quanta
R 1
J 0
(9075 10825);
DISPLAY INVISIBLE (9075 10825);
FORCEPROP 1 LAST MATERIAL X7R
R 1
J 0
(9075 10875);
DISPLAY 0.638298 (9075 10875);
DISPLAY INVISIBLE (9075 10875);
FORCEPROP 1 LAST TOLERANCE 10%
R 1
J 0
(9125 10875);
DISPLAY 0.638298 (9125 10875);
DISPLAY INVISIBLE (9125 10875);
FORCEPROP 1 LAST PATH I77
R 1
J 0
(8925 10875);
DISPLAY 0.978723 (8925 10875);
PAINT WHITE (8925 10875);
DISPLAY INVISIBLE (8925 10875);
FORCEPROP 1 LAST PART_NUMBER CH23906KB14
J 0
(9125 10825);
DISPLAY 0.510638 (9125 10825);
DISPLAY INVISIBLE (9125 10825);
FORCEADD GND..1
(8575 12100);
FORCEPROP 3 LASTPIN (8575 12150) SIG_NAME GND\g
J 0
(8585 12160);
DISPLAY 0.659574 (8585 12160);
PAINT MONO (8585 12160);
DISPLAY INVISIBLE (8585 12160);
FORCEPROP 2 LAST CDS_LIB pure_quanta_power
J 0
(8575 12100);
DISPLAY INVISIBLE (8575 12100);
FORCEPROP 1 LAST SIZE 1B
J 0
(8650 12050);
DISPLAY 0.872340 (8650 12050);
PAINT GREEN (8650 12050);
DISPLAY INVISIBLE (8650 12050);
FORCEPROP 1 LAST HDL_POWER GND
J 0
(8575 12250);
DISPLAY 0.872340 (8575 12250);
PAINT GREEN (8575 12250);
DISPLAY INVISIBLE (8575 12250);
FORCEPROP 1 LAST PATH I78
J 0
(8650 12100);
DISPLAY 0.872340 (8650 12100);
PAINT AQUA (8650 12100);
DISPLAY INVISIBLE (8650 12100);
FORCEADD SCHOTTKY_AC..1
R 1
(8825 11700);
FORCEPROP 1 LAST LOCATION PD102
J 0
(8875 11725);
DISPLAY 0.723404 (8875 11725);
PAINT GREEN (8875 11725);
FORCEPROP 0 LAST $SEC 1
R 1
J 0
(8875 11775);
DISPLAY INVISIBLE (8875 11775);
FORCEPROP 0 LAST CDS_SEC 1
R 1
J 0
(8875 11775);
DISPLAY INVISIBLE (8875 11775);
FORCEPROP 0 LASTPIN (8825 11575) $PN A
R 1
J 2
(8815 11610);
DISPLAY 0.808511 (8815 11610);
FORCEPROP 0 LASTPIN (8825 11825) $PN C
R 1
J 0
(8815 11785);
DISPLAY 0.808511 (8815 11785);
FORCEPROP 2 LAST VALUE B340A-13-F
J 0
(8875 11675);
DISPLAY 0.638298 (8875 11675);
FORCEPROP 1 LAST MATERIAL IC
J 0
(8875 11600);
DISPLAY 0.723404 (8875 11600);
PAINT GREEN (8875 11600);
FORCEPROP 1 LAST CDS_LMAN_SYM_OUTLINE -75,50,75,-50
R 1
J 0
(8825 11700);
DISPLAY 0.468085 (8825 11700);
PAINT GREEN (8825 11700);
DISPLAY INVISIBLE (8825 11700);
FORCEPROP 2 LAST CDS_LIB pure_quanta
R 1
J 0
(8825 11700);
DISPLAY INVISIBLE (8825 11700);
FORCEPROP 1 LAST NEEDS_NO_SIZE TRUE
R 1
J 0
(8875 11775);
DISPLAY 0.468085 (8875 11775);
PAINT GREEN (8875 11775);
DISPLAY INVISIBLE (8875 11775);
FORCEPROP 0 LAST PART_TYPE SMLF
J 0
(8875 11875);
DISPLAY 1.021277 (8875 11875);
DISPLAY INVISIBLE (8875 11875);
FORCEPROP 1 LAST PATH I79
R 1
J 0
(8825 11700);
DISPLAY 0.723404 (8825 11700);
PAINT GREEN (8825 11700);
DISPLAY INVISIBLE (8825 11700);
FORCEPROP 1 LAST PART_NUMBER BC000340Z30
J 0
(8875 11625);
DISPLAY 0.595745 (8875 11625);
PAINT GREEN (8875 11625);
DISPLAY INVISIBLE (8875 11625);
FORCEADD OFFPAGE..1
(3725 8500);
FORCEPROP 2 LAST $XR1 143 
J 0
(3323 8500);
DISPLAY 0.638298 (3323 8500);
PAINT MONO (3323 8500);
FORCEPROP 2 LAST $XR0 131 
J 0
(3443 8500);
DISPLAY 0.638298 (3443 8500);
PAINT MONO (3443 8500);
FORCEPROP 2 LAST CDS_LIB standard
J 0
(3725 8500);
PAINT MONO (3725 8500);
DISPLAY INVISIBLE (3725 8500);
FORCEPROP 1 LAST OFFPAGE TRUE
J 0
(4050 8375);
DISPLAY 0.872340 (4050 8375);
PAINT GREEN (4050 8375);
DISPLAY INVISIBLE (4050 8375);
FORCEPROP 1 LAST COMMENT_BODY TRUE
J 0
(3850 8400);
DISPLAY 0.872340 (3850 8400);
PAINT GREEN (3850 8400);
DISPLAY INVISIBLE (3850 8400);
FORCEPROP 2 LAST PATH I8
J 0
(3475 8550);
DISPLAY 0.680851 (3475 8550);
DISPLAY INVISIBLE (3475 8550);
FORCEADD Q_RES..1
(9375 10400);
FORCEPROP 1 LAST LOCATION R3870
J 0
(9175 10400);
DISPLAY 0.638298 (9175 10400);
FORCEPROP 0 LAST $SEC 1
J 0
(9325 10500);
DISPLAY 0.680851 (9325 10500);
PAINT MONO (9325 10500);
DISPLAY INVISIBLE (9325 10500);
FORCEPROP 0 LAST CDS_SEC 1
J 0
(9325 10500);
DISPLAY 1.021277 (9325 10500);
DISPLAY INVISIBLE (9325 10500);
FORCEPROP 1 LASTPIN (9275 10400) $PN 1
J 0
(9287 10412);
DISPLAY 0.787234 (9287 10412);
PAINT MONO (9287 10412);
FORCEPROP 1 LASTPIN (9475 10400) $PN 2
J 0
(9437 10412);
DISPLAY 0.787234 (9437 10412);
PAINT MONO (9437 10412);
FORCEPROP 1 LAST WATTAGE 1/16W
J 2
(9175 10350);
DISPLAY 0.595745 (9175 10350);
FORCEPROP 1 LAST MATERIAL CHIP
J 0
(9025 10400);
DISPLAY 0.595745 (9025 10400);
FORCEPROP 1 LAST VALUE 0
J 2
(9525 10400);
DISPLAY 0.595745 (9525 10400);
FORCEPROP 1 LAST PACK_TYPE 0402LF
J 0
(9525 10350);
DISPLAY 0.595745 (9525 10350);
FORCEPROP 1 LAST TOLERANCE 5%
J 0
(9550 10400);
DISPLAY 0.595745 (9550 10400);
FORCEPROP 0 LAST ROOM NIC_P12V_MAM_TIC_BOM1
J 0
(9075 10300);
DISPLAY 0.553191 (9075 10300);
PAINT RED (9075 10300);
FORCEPROP 2 LAST CDS_LIB pure_quanta
J 0
(9375 10400);
DISPLAY INVISIBLE (9375 10400);
FORCEPROP 1 LAST PATH I80
J 0
(9325 10550);
DISPLAY 0.978723 (9325 10550);
PAINT WHITE (9325 10550);
DISPLAY INVISIBLE (9325 10550);
FORCEPROP 1 LAST PART_NUMBER CS00002JB13
J 0
(9200 10350);
DISPLAY 0.595745 (9200 10350);
DISPLAY INVISIBLE (9200 10350);
FORCEADD GND..1
(9200 10750);
FORCEPROP 3 LASTPIN (9200 10800) SIG_NAME GND\g
J 0
(9210 10810);
DISPLAY 0.659574 (9210 10810);
PAINT MONO (9210 10810);
DISPLAY INVISIBLE (9210 10810);
FORCEPROP 1 LAST SIZE 1B
J 0
(9275 10700);
DISPLAY 0.872340 (9275 10700);
PAINT GREEN (9275 10700);
DISPLAY INVISIBLE (9275 10700);
FORCEPROP 2 LAST CDS_LIB pure_quanta_power
J 0
(9200 10750);
DISPLAY INVISIBLE (9200 10750);
FORCEPROP 1 LAST HDL_POWER GND
J 0
(9200 10900);
DISPLAY 0.872340 (9200 10900);
PAINT GREEN (9200 10900);
DISPLAY INVISIBLE (9200 10900);
FORCEPROP 1 LAST PATH I81
J 0
(9275 10750);
DISPLAY 0.872340 (9275 10750);
PAINT AQUA (9275 10750);
DISPLAY INVISIBLE (9275 10750);
FORCEADD Q_RES..1
(9375 10525);
FORCEPROP 1 LAST LOCATION R3869
J 0
(9175 10525);
DISPLAY 0.638298 (9175 10525);
FORCEPROP 0 LAST $SEC 1
J 0
(9325 10625);
DISPLAY 0.680851 (9325 10625);
PAINT MONO (9325 10625);
DISPLAY INVISIBLE (9325 10625);
FORCEPROP 0 LAST CDS_SEC 1
J 0
(9325 10625);
DISPLAY 1.021277 (9325 10625);
DISPLAY INVISIBLE (9325 10625);
FORCEPROP 1 LASTPIN (9275 10525) $PN 1
J 0
(9287 10537);
DISPLAY 0.787234 (9287 10537);
PAINT MONO (9287 10537);
FORCEPROP 1 LASTPIN (9475 10525) $PN 2
J 0
(9437 10537);
DISPLAY 0.787234 (9437 10537);
PAINT MONO (9437 10537);
FORCEPROP 1 LAST MATERIAL EMPTY
J 0
(9025 10525);
DISPLAY 0.595745 (9025 10525);
PAINT RED (9025 10525);
FORCEPROP 1 LAST VALUE 0
J 2
(9525 10525);
DISPLAY 0.595745 (9525 10525);
FORCEPROP 1 LAST WATTAGE 1/16W
J 2
(9175 10475);
DISPLAY 0.595745 (9175 10475);
FORCEPROP 1 LAST PACK_TYPE 0402LF
J 0
(9525 10475);
DISPLAY 0.595745 (9525 10475);
FORCEPROP 1 LAST TOLERANCE 5%
J 0
(9550 10525);
DISPLAY 0.595745 (9550 10525);
FORCEPROP 2 LAST CDS_LIB pure_quanta
J 0
(9375 10525);
DISPLAY INVISIBLE (9375 10525);
FORCEPROP 1 LAST PATH I82
J 0
(9325 10675);
DISPLAY 0.978723 (9325 10675);
PAINT WHITE (9325 10675);
DISPLAY INVISIBLE (9325 10675);
FORCEPROP 1 LAST PART_NUMBER CS00002JB13
J 0
(9200 10475);
DISPLAY 0.595745 (9200 10475);
DISPLAY INVISIBLE (9200 10475);
FORCEADD Q_RES..2
(9475 11000);
FORCEPROP 1 LAST LOCATION R3799
J 0
(9520 11125);
DISPLAY 0.638298 (9520 11125);
FORCEPROP 0 LAST $SEC 1
J 0
(9525 11175);
DISPLAY 0.680851 (9525 11175);
PAINT MONO (9525 11175);
DISPLAY INVISIBLE (9525 11175);
FORCEPROP 0 LAST CDS_SEC 1
J 0
(9525 11175);
DISPLAY 1.021277 (9525 11175);
DISPLAY INVISIBLE (9525 11175);
FORCEPROP 1 LASTPIN (9475 11100) $PN 1
J 0
(9480 11062);
DISPLAY 0.787234 (9480 11062);
PAINT MONO (9480 11062);
FORCEPROP 1 LASTPIN (9475 10900) $PN 2
J 0
(9480 10910);
DISPLAY 0.787234 (9480 10910);
PAINT MONO (9480 10910);
FORCEPROP 1 LAST VALUE 100K
J 0
(9520 11075);
DISPLAY 0.510638 (9520 11075);
FORCEPROP 0 LAST ROOM NIC_P12V_MAM_TIC_BOM1
J 0
(9525 11175);
DISPLAY 0.361702 (9525 11175);
PAINT RED (9525 11175);
FORCEPROP 1 LAST MATERIAL CHIP
J 0
(9515 10925);
DISPLAY 0.510638 (9515 10925);
FORCEPROP 1 LAST PACK_TYPE 0402LF
J 0
(9515 10825);
DISPLAY 0.510638 (9515 10825);
FORCEPROP 1 LAST WATTAGE 1/16W
J 0
(9515 10975);
DISPLAY 0.510638 (9515 10975);
FORCEPROP 1 LAST TOLERANCE 1%
J 0
(9520 11025);
DISPLAY 0.510638 (9520 11025);
FORCEPROP 2 LAST CDS_LIB pure_quanta
J 0
(9475 11000);
DISPLAY INVISIBLE (9475 11000);
FORCEPROP 1 LAST PATH I83
J 0
(9525 11175);
DISPLAY 0.978723 (9525 11175);
PAINT WHITE (9525 11175);
DISPLAY INVISIBLE (9525 11175);
FORCEPROP 1 LAST PART_NUMBER CS41002FB09
J 0
(9515 10875);
DISPLAY 0.510638 (9515 10875);
DISPLAY INVISIBLE (9515 10875);
FORCEADD VCCAUX15..1
(9650 11300);
FORCEPROP 3 LASTPIN (9650 11250) SIG_NAME P3V3_AUX\g
J 0
(9660 11260);
DISPLAY 0.659574 (9660 11260);
PAINT MONO (9660 11260);
DISPLAY INVISIBLE (9660 11260);
FORCEPROP 1 LAST HDL_POWER P3V3_AUX
J 1
(9650 11350);
DISPLAY 0.723404 (9650 11350);
PAINT GREEN (9650 11350);
FORCEPROP 2 LAST CDS_LIB pure_quanta_power
J 0
(9650 11300);
DISPLAY INVISIBLE (9650 11300);
FORCEPROP 1 LAST PATH I84
J 0
(9700 11325);
DISPLAY 0.872340 (9700 11325);
PAINT AQUA (9700 11325);
DISPLAY INVISIBLE (9700 11325);
FORCEADD Q_RES..2
(9900 11000);
FORCEPROP 1 LAST LOCATION R3797
J 0
(9945 11125);
DISPLAY 0.638298 (9945 11125);
FORCEPROP 0 LAST $SEC 1
J 0
(9950 11175);
DISPLAY 0.680851 (9950 11175);
PAINT MONO (9950 11175);
DISPLAY INVISIBLE (9950 11175);
FORCEPROP 0 LAST CDS_SEC 1
J 0
(9950 11175);
DISPLAY 1.021277 (9950 11175);
DISPLAY INVISIBLE (9950 11175);
FORCEPROP 1 LASTPIN (9900 11100) $PN 1
J 0
(9905 11062);
DISPLAY 0.787234 (9905 11062);
PAINT MONO (9905 11062);
FORCEPROP 1 LASTPIN (9900 10900) $PN 2
J 0
(9905 10910);
DISPLAY 0.787234 (9905 10910);
PAINT MONO (9905 10910);
FORCEPROP 1 LAST TOLERANCE 1%
J 0
(9945 11025);
DISPLAY 0.510638 (9945 11025);
FORCEPROP 1 LAST WATTAGE 1/16W
J 0
(9940 10975);
DISPLAY 0.510638 (9940 10975);
FORCEPROP 1 LAST MATERIAL CHIP
J 0
(9940 10925);
DISPLAY 0.510638 (9940 10925);
FORCEPROP 1 LAST PACK_TYPE 0402LF
J 0
(9940 10825);
DISPLAY 0.510638 (9940 10825);
FORCEPROP 0 LAST ROOM NIC_P12V_MAM_TIC_BOM1
J 0
(9950 11175);
DISPLAY 0.446809 (9950 11175);
PAINT RED (9950 11175);
FORCEPROP 1 LAST VALUE 100K
J 0
(9945 11075);
DISPLAY 0.510638 (9945 11075);
FORCEPROP 2 LAST CDS_LIB pure_quanta
J 0
(9900 11000);
DISPLAY INVISIBLE (9900 11000);
FORCEPROP 1 LAST PATH I85
J 0
(9950 11175);
DISPLAY 0.978723 (9950 11175);
PAINT WHITE (9950 11175);
DISPLAY INVISIBLE (9950 11175);
FORCEPROP 1 LAST PART_NUMBER CS41002FB09
J 0
(9940 10875);
DISPLAY 0.510638 (9940 10875);
DISPLAY INVISIBLE (9940 10875);
FORCEADD Q_CAP..1
(9300 11675);
FORCEPROP 1 LAST LOCATION PC2092
J 0
(9350 11775);
DISPLAY 0.638298 (9350 11775);
FORCEPROP 0 LAST $SEC 1
J 0
(9350 11825);
DISPLAY 0.680851 (9350 11825);
PAINT MONO (9350 11825);
DISPLAY INVISIBLE (9350 11825);
FORCEPROP 0 LAST CDS_SEC 1
J 0
(9350 11825);
DISPLAY 1.021277 (9350 11825);
DISPLAY INVISIBLE (9350 11825);
FORCEPROP 1 LASTPIN (9300 11775) $PN 1
J 0
(9310 11755);
DISPLAY 0.787234 (9310 11755);
PAINT MONO (9310 11755);
DISPLAY INVISIBLE (9310 11755);
FORCEPROP 1 LASTPIN (9300 11575) $PN 2
J 0
(9310 11555);
DISPLAY 0.787234 (9310 11555);
PAINT MONO (9310 11555);
DISPLAY INVISIBLE (9310 11555);
FORCEPROP 1 LAST PACK_TYPE 0402
J 0
(9350 11575);
DISPLAY 0.638298 (9350 11575);
FORCEPROP 1 LAST MATERIAL X7R
J 0
(9350 11625);
DISPLAY 0.638298 (9350 11625);
FORCEPROP 1 LAST VOLTAGE 25V
J 0
(9350 11675);
DISPLAY 0.638298 (9350 11675);
FORCEPROP 1 LAST VALUE 0.1UF
J 0
(9350 11725);
DISPLAY 0.638298 (9350 11725);
FORCEPROP 2 LAST CDS_LIB pure_quanta
J 0
(9300 11675);
DISPLAY INVISIBLE (9300 11675);
FORCEPROP 1 LAST TOLERANCE 10%
J 0
(9350 11625);
DISPLAY 0.978723 (9350 11625);
DISPLAY INVISIBLE (9350 11625);
FORCEPROP 1 LAST PATH I86
J 0
(9350 11825);
DISPLAY 0.978723 (9350 11825);
PAINT WHITE (9350 11825);
DISPLAY INVISIBLE (9350 11825);
FORCEPROP 1 LAST PART_NUMBER CH4104K1B00
J 0
(9350 11525);
DISPLAY 0.638298 (9350 11525);
DISPLAY INVISIBLE (9350 11525);
FORCEADD Q_CAP..1
(9725 11675);
FORCEPROP 1 LAST LOCATION PC2080
J 0
(9775 11775);
DISPLAY 0.638298 (9775 11775);
FORCEPROP 0 LAST $SEC 1
J 0
(9775 11825);
DISPLAY INVISIBLE (9775 11825);
FORCEPROP 0 LAST CDS_SEC 1
J 0
(9775 11825);
DISPLAY INVISIBLE (9775 11825);
FORCEPROP 1 LASTPIN (9725 11775) $PN 1
J 0
(9735 11755);
DISPLAY 0.787234 (9735 11755);
PAINT MONO (9735 11755);
DISPLAY INVISIBLE (9735 11755);
FORCEPROP 1 LASTPIN (9725 11575) $PN 2
J 0
(9735 11555);
DISPLAY 0.787234 (9735 11555);
PAINT MONO (9735 11555);
DISPLAY INVISIBLE (9735 11555);
FORCEPROP 1 LAST PACK_TYPE C0805
J 0
(9775 11575);
DISPLAY 0.638298 (9775 11575);
FORCEPROP 1 LAST VALUE 22UF
J 0
(9775 11725);
DISPLAY 0.638298 (9775 11725);
FORCEPROP 1 LAST MATERIAL X6S
J 0
(9775 11625);
DISPLAY 0.638298 (9775 11625);
FORCEPROP 1 LAST VOLTAGE 16V
J 0
(9775 11675);
DISPLAY 0.638298 (9775 11675);
FORCEPROP 2 LAST CDS_LIB pure_quanta
J 0
(9725 11675);
DISPLAY INVISIBLE (9725 11675);
FORCEPROP 1 LAST TOLERANCE 20%
J 0
(9775 11625);
DISPLAY 0.978723 (9775 11625);
DISPLAY INVISIBLE (9775 11625);
FORCEPROP 1 LAST PATH I87
J 0
(9775 11825);
DISPLAY 0.978723 (9775 11825);
PAINT WHITE (9775 11825);
DISPLAY INVISIBLE (9775 11825);
FORCEPROP 1 LAST PART_NUMBER CH6223MEA01
J 0
(9775 11525);
DISPLAY 0.638298 (9775 11525);
DISPLAY INVISIBLE (9775 11525);
FORCEADD GND..1
(10125 11325);
FORCEPROP 3 LASTPIN (10125 11375) SIG_NAME GND\g
J 0
(10135 11385);
DISPLAY 0.659574 (10135 11385);
PAINT MONO (10135 11385);
DISPLAY INVISIBLE (10135 11385);
FORCEPROP 2 LAST CDS_LIB pure_quanta_power
J 0
(10125 11325);
DISPLAY INVISIBLE (10125 11325);
FORCEPROP 1 LAST SIZE 1B
J 0
(10200 11275);
DISPLAY 0.872340 (10200 11275);
PAINT GREEN (10200 11275);
DISPLAY INVISIBLE (10200 11275);
FORCEPROP 1 LAST HDL_POWER GND
J 0
(10125 11475);
DISPLAY 0.872340 (10125 11475);
PAINT GREEN (10125 11475);
DISPLAY INVISIBLE (10125 11475);
FORCEPROP 1 LAST PATH I88
J 0
(10200 11325);
DISPLAY 0.872340 (10200 11325);
PAINT AQUA (10200 11325);
DISPLAY INVISIBLE (10200 11325);
FORCEADD Q_CAP..1
(10125 11675);
FORCEPROP 1 LAST LOCATION PC2082
J 0
(10175 11775);
DISPLAY 0.680851 (10175 11775);
FORCEPROP 0 LAST $SEC 1
J 0
(10175 11825);
DISPLAY INVISIBLE (10175 11825);
FORCEPROP 0 LAST CDS_SEC 1
J 0
(10175 11825);
DISPLAY INVISIBLE (10175 11825);
FORCEPROP 1 LASTPIN (10125 11775) $PN 1
J 0
(10135 11755);
DISPLAY 0.787234 (10135 11755);
PAINT MONO (10135 11755);
DISPLAY INVISIBLE (10135 11755);
FORCEPROP 1 LASTPIN (10125 11575) $PN 2
J 0
(10135 11555);
DISPLAY 0.787234 (10135 11555);
PAINT MONO (10135 11555);
DISPLAY INVISIBLE (10135 11555);
FORCEPROP 1 LAST VALUE 10UF
J 0
(10175 11725);
DISPLAY 0.638298 (10175 11725);
FORCEPROP 1 LAST VOLTAGE 16V
J 0
(10175 11675);
DISPLAY 0.638298 (10175 11675);
FORCEPROP 1 LAST MATERIAL X6S
J 0
(10175 11625);
DISPLAY 0.638298 (10175 11625);
FORCEPROP 1 LAST PACK_TYPE C0805
J 0
(10175 11575);
DISPLAY 0.638298 (10175 11575);
FORCEPROP 2 LAST CDS_LIB pure_quanta
J 0
(10125 11675);
DISPLAY INVISIBLE (10125 11675);
FORCEPROP 1 LAST TOLERANCE 10%
J 0
(9914 11635);
DISPLAY 0.787234 (9914 11635);
PAINT GREEN (9914 11635);
DISPLAY INVISIBLE (9914 11635);
FORCEPROP 1 LAST PATH I89
J 0
(10175 11825);
DISPLAY 0.978723 (10175 11825);
PAINT WHITE (10175 11825);
DISPLAY INVISIBLE (10175 11825);
FORCEPROP 1 LAST PART_NUMBER CH6103KEA01
J 0
(10175 11525);
DISPLAY 0.638298 (10175 11525);
DISPLAY INVISIBLE (10175 11525);
FORCEADD Q_RES..2
(3900 8850);
FORCEPROP 1 LAST LOCATION R1906
J 0
(3945 8975);
DISPLAY 0.978723 (3945 8975);
FORCEPROP 0 LAST $SEC 1
J 0
(3950 9025);
DISPLAY 0.680851 (3950 9025);
PAINT MONO (3950 9025);
DISPLAY INVISIBLE (3950 9025);
FORCEPROP 0 LAST CDS_SEC 1
J 0
(3950 9025);
DISPLAY 1.021277 (3950 9025);
DISPLAY INVISIBLE (3950 9025);
FORCEPROP 1 LASTPIN (3900 8950) $PN 1
J 0
(3905 8912);
DISPLAY 0.787234 (3905 8912);
PAINT MONO (3905 8912);
FORCEPROP 1 LASTPIN (3900 8750) $PN 2
J 0
(3905 8760);
DISPLAY 0.787234 (3905 8760);
PAINT MONO (3905 8760);
FORCEPROP 1 LAST VALUE 1K
J 0
(3945 8925);
DISPLAY 0.638298 (3945 8925);
FORCEPROP 1 LAST TOLERANCE 1%
J 0
(3945 8875);
DISPLAY 0.638298 (3945 8875);
FORCEPROP 1 LAST PACK_TYPE 0402LF
J 0
(3940 8725);
DISPLAY 0.638298 (3940 8725);
FORCEPROP 1 LAST WATTAGE 1/16W
J 0
(3940 8825);
DISPLAY 0.638298 (3940 8825);
FORCEPROP 1 LAST MATERIAL CHIP
J 0
(3940 8775);
DISPLAY 0.638298 (3940 8775);
FORCEPROP 2 LAST CDS_LIB pure_quanta
J 0
(3900 8850);
DISPLAY INVISIBLE (3900 8850);
FORCEPROP 1 LAST PATH I9
J 0
(3950 9025);
DISPLAY 0.978723 (3950 9025);
PAINT WHITE (3950 9025);
DISPLAY INVISIBLE (3950 9025);
FORCEPROP 1 LAST PART_NUMBER CS21002FB06
J 0
(3940 8725);
DISPLAY 0.638298 (3940 8725);
DISPLAY INVISIBLE (3940 8725);
FORCEADD UNIVERSAL_POWER..1
R 2
(10125 11975);
FORCEPROP 3 LASTPIN (10125 11925) SIG_NAME P12V_OCP_SFF\g
J 0
(10135 11935);
DISPLAY 0.659574 (10135 11935);
PAINT MONO (10135 11935);
DISPLAY INVISIBLE (10135 11935);
FORCEPROP 1 LAST HDL_POWER P12V_OCP_SFF
J 1
(10125 12025);
DISPLAY 0.723404 (10125 12025);
PAINT GREEN (10125 12025);
FORCEPROP 2 LAST CDS_LIB pure_quanta_power
J 0
(10125 11975);
DISPLAY INVISIBLE (10125 11975);
FORCEPROP 1 LAST PATH I90
J 2
(10075 12000);
DISPLAY 0.872340 (10075 12000);
PAINT AQUA (10075 12000);
DISPLAY INVISIBLE (10075 12000);
FORCEADD OFFPAGE..2
(10375 10725);
PAINT AQUA (10375 10725);
FORCEPROP 2 LAST $XR3 248 
J 0
(10564 10689);
DISPLAY 0.638298 (10564 10689);
PAINT MONO (10564 10689);
FORCEPROP 2 LAST $XR2 136 
J 0
(10804 10725);
DISPLAY 0.638298 (10804 10725);
PAINT MONO (10804 10725);
FORCEPROP 2 LAST $XR1 134 
J 0
(10684 10725);
DISPLAY 0.638298 (10684 10725);
PAINT MONO (10684 10725);
FORCEPROP 2 LAST $XR0 135 
J 0
(10564 10725);
DISPLAY 0.638298 (10564 10725);
PAINT MONO (10564 10725);
FORCEPROP 2 LAST CDS_LIB standard
J 0
(10375 10725);
DISPLAY INVISIBLE (10375 10725);
FORCEPROP 1 LAST OFFPAGE TRUE
J 0
(10700 10600);
DISPLAY 0.872340 (10700 10600);
PAINT AQUA (10700 10600);
DISPLAY INVISIBLE (10700 10600);
FORCEPROP 1 LAST COMMENT_BODY TRUE
J 0
(10330 10630);
DISPLAY 0.872340 (10330 10630);
PAINT GREEN (10330 10630);
DISPLAY INVISIBLE (10330 10630);
FORCEPROP 2 LAST PATH I91
J 0
(10825 10775);
DISPLAY 0.680851 (10825 10775);
DISPLAY INVISIBLE (10825 10775);
FORCEADD OFFPAGE..2
(10625 10400);
PAINT AQUA (10625 10400);
FORCEPROP 2 LAST $XR0 258 
J 0
(10814 10400);
DISPLAY 0.638298 (10814 10400);
PAINT MONO (10814 10400);
FORCEPROP 2 LAST CDS_LIB standard
J 0
(10625 10400);
DISPLAY INVISIBLE (10625 10400);
FORCEPROP 1 LAST OFFPAGE TRUE
J 0
(10950 10275);
DISPLAY 0.872340 (10950 10275);
PAINT AQUA (10950 10275);
DISPLAY INVISIBLE (10950 10275);
FORCEPROP 1 LAST COMMENT_BODY TRUE
J 0
(10580 10305);
DISPLAY 0.872340 (10580 10305);
PAINT GREEN (10580 10305);
DISPLAY INVISIBLE (10580 10305);
FORCEPROP 2 LAST PATH I92
J 0
(10825 10450);
DISPLAY 0.680851 (10825 10450);
DISPLAY INVISIBLE (10825 10450);
FORCEADD OFFPAGE..2
(10625 10525);
PAINT AQUA (10625 10525);
FORCEPROP 2 LAST $XR0 258 
J 0
(10814 10525);
DISPLAY 0.638298 (10814 10525);
PAINT MONO (10814 10525);
FORCEPROP 2 LAST CDS_LIB standard
J 0
(10625 10525);
DISPLAY INVISIBLE (10625 10525);
FORCEPROP 1 LAST OFFPAGE TRUE
J 0
(10950 10400);
DISPLAY 0.872340 (10950 10400);
PAINT AQUA (10950 10400);
DISPLAY INVISIBLE (10950 10400);
FORCEPROP 1 LAST COMMENT_BODY TRUE
J 0
(10580 10430);
DISPLAY 0.872340 (10580 10430);
PAINT GREEN (10580 10430);
DISPLAY INVISIBLE (10580 10430);
FORCEPROP 2 LAST PATH I93
J 0
(10825 10575);
DISPLAY 0.680851 (10825 10575);
DISPLAY INVISIBLE (10825 10575);
FORCEADD Q_CAP..1
(8675 13100);
FORCEPROP 1 LAST LOCATION PC2144
J 0
(8725 13200);
DISPLAY 0.638298 (8725 13200);
FORCEPROP 0 LAST $SEC 1
J 0
(8725 13250);
DISPLAY 0.680851 (8725 13250);
PAINT MONO (8725 13250);
DISPLAY INVISIBLE (8725 13250);
FORCEPROP 0 LAST CDS_SEC 1
J 0
(8725 13250);
DISPLAY 1.021277 (8725 13250);
DISPLAY INVISIBLE (8725 13250);
FORCEPROP 1 LASTPIN (8675 13200) $PN 1
J 0
(8685 13180);
DISPLAY 0.787234 (8685 13180);
PAINT MONO (8685 13180);
DISPLAY INVISIBLE (8685 13180);
FORCEPROP 1 LASTPIN (8675 13000) $PN 2
J 0
(8685 12980);
DISPLAY 0.787234 (8685 12980);
PAINT MONO (8685 12980);
DISPLAY INVISIBLE (8685 12980);
FORCEPROP 1 LAST VOLTAGE 50V
J 0
(8730 13092);
DISPLAY 0.638298 (8730 13092);
FORCEPROP 1 LAST MATERIAL EMPTY
J 0
(8725 13000);
DISPLAY 0.638298 (8725 13000);
PAINT RED (8725 13000);
FORCEPROP 1 LAST PACK_TYPE C0402
J 0
(8730 13042);
DISPLAY 0.638298 (8730 13042);
FORCEPROP 0 LAST ROOM NIC_P3V3_BOM1
J 0
(8700 12975);
DISPLAY 0.361702 (8700 12975);
PAINT RED (8700 12975);
FORCEPROP 1 LAST VALUE 0.01UF
J 0
(8725 13150);
DISPLAY 0.638298 (8725 13150);
FORCEPROP 2 LAST CDS_LIB pure_quanta
J 0
(8675 13100);
DISPLAY INVISIBLE (8675 13100);
FORCEPROP 1 LAST TOLERANCE 10%
J 0
(8725 13050);
DISPLAY 0.638298 (8725 13050);
DISPLAY INVISIBLE (8725 13050);
FORCEPROP 1 LAST PATH I94
J 0
(8725 13250);
DISPLAY 0.978723 (8725 13250);
PAINT WHITE (8725 13250);
DISPLAY INVISIBLE (8725 13250);
FORCEPROP 1 LAST PART_NUMBER CH31006KB18
J 0
(8730 12992);
DISPLAY 0.638298 (8730 12992);
DISPLAY INVISIBLE (8730 12992);
FORCEADD Q_RES..2
(8700 12425);
FORCEPROP 1 LAST LOCATION PR5481
J 0
(8745 12550);
DISPLAY 0.638298 (8745 12550);
FORCEPROP 0 LAST $SEC 1
J 0
(8750 12600);
DISPLAY 0.680851 (8750 12600);
PAINT MONO (8750 12600);
DISPLAY INVISIBLE (8750 12600);
FORCEPROP 0 LAST CDS_SEC 1
J 0
(8750 12600);
DISPLAY 1.021277 (8750 12600);
DISPLAY INVISIBLE (8750 12600);
FORCEPROP 1 LASTPIN (8700 12525) $PN 1
J 0
(8705 12487);
DISPLAY 0.787234 (8705 12487);
PAINT MONO (8705 12487);
FORCEPROP 1 LASTPIN (8700 12325) $PN 2
J 0
(8705 12335);
DISPLAY 0.787234 (8705 12335);
PAINT MONO (8705 12335);
FORCEPROP 1 LAST MATERIAL CHIP
J 0
(8740 12350);
DISPLAY 0.404255 (8740 12350);
FORCEPROP 1 LAST PACK_TYPE 0402LF
J 0
(8740 12250);
DISPLAY 0.404255 (8740 12250);
FORCEPROP 1 LAST WATTAGE 1/16W
J 0
(8740 12400);
DISPLAY 0.404255 (8740 12400);
FORCEPROP 0 LAST ROOM NIC_P3V3_BOM1
J 0
(8725 12200);
DISPLAY 0.553191 (8725 12200);
PAINT RED (8725 12200);
FORCEPROP 1 LAST VALUE 4.53K
J 0
(8745 12500);
DISPLAY 0.404255 (8745 12500);
FORCEPROP 1 LAST TOLERANCE 1%
J 0
(8745 12450);
DISPLAY 0.404255 (8745 12450);
FORCEPROP 2 LAST CDS_LIB pure_quanta
J 0
(8700 12425);
DISPLAY INVISIBLE (8700 12425);
FORCEPROP 1 LAST PATH I95
J 0
(8750 12600);
DISPLAY 0.978723 (8750 12600);
PAINT WHITE (8750 12600);
DISPLAY INVISIBLE (8750 12600);
FORCEPROP 1 LAST PART_NUMBER CS24532FB03
J 0
(8740 12300);
DISPLAY 0.404255 (8740 12300);
DISPLAY INVISIBLE (8740 12300);
FORCEADD Q_RES..2
(8925 13100);
FORCEPROP 1 LAST LOCATION PR4525
J 0
(8975 13250);
DISPLAY 0.510638 (8975 13250);
FORCEPROP 0 LAST $SEC 1
J 0
(8975 13275);
DISPLAY 0.680851 (8975 13275);
PAINT MONO (8975 13275);
DISPLAY INVISIBLE (8975 13275);
FORCEPROP 0 LAST CDS_SEC 1
J 0
(8975 13275);
DISPLAY 1.021277 (8975 13275);
DISPLAY INVISIBLE (8975 13275);
FORCEPROP 1 LASTPIN (8925 13200) $PN 1
J 0
(8930 13162);
DISPLAY 0.787234 (8930 13162);
PAINT MONO (8930 13162);
FORCEPROP 1 LASTPIN (8925 13000) $PN 2
J 0
(8930 13010);
DISPLAY 0.787234 (8930 13010);
PAINT MONO (8930 13010);
FORCEPROP 1 LAST MATERIAL CHIP
J 0
(8975 13125);
DISPLAY 0.510638 (8975 13125);
FORCEPROP 0 LAST ROOM NIC_P3V3_BOM1
J 0
(8975 13275);
DISPLAY 0.553191 (8975 13275);
PAINT RED (8975 13275);
FORCEPROP 1 LAST PACK_TYPE 0402LF
J 0
(8975 13075);
DISPLAY 0.510638 (8975 13075);
FORCEPROP 1 LAST TOLERANCE 1%
J 0
(8975 13175);
DISPLAY 0.510638 (8975 13175);
FORCEPROP 1 LAST VALUE 10M
J 0
(8975 13225);
DISPLAY 0.510638 (8975 13225);
FORCEPROP 1 LAST WATTAGE 1/16W
J 0
(8975 13150);
DISPLAY 0.510638 (8975 13150);
FORCEPROP 2 LAST CDS_LIB pure_quanta
J 0
(8925 13100);
DISPLAY INVISIBLE (8925 13100);
FORCEPROP 1 LAST PATH I96
J 0
(8975 13275);
DISPLAY 0.978723 (8975 13275);
PAINT WHITE (8975 13275);
DISPLAY INVISIBLE (8975 13275);
FORCEPROP 1 LAST PART_NUMBER CS61002FB02
J 0
(8975 13100);
DISPLAY 0.510638 (8975 13100);
DISPLAY INVISIBLE (8975 13100);
FORCEADD SCHOTTKY_AC..1
R 1
(9050 13675);
FORCEPROP 1 LAST LOCATION PD103
J 0
(9100 13700);
DISPLAY 0.723404 (9100 13700);
PAINT GREEN (9100 13700);
FORCEPROP 0 LAST $SEC 1
R 1
J 0
(9100 13750);
DISPLAY INVISIBLE (9100 13750);
FORCEPROP 0 LAST CDS_SEC 1
R 1
J 0
(9100 13750);
DISPLAY INVISIBLE (9100 13750);
FORCEPROP 0 LASTPIN (9050 13550) $PN A
R 1
J 2
(9040 13585);
DISPLAY 0.808511 (9040 13585);
FORCEPROP 0 LASTPIN (9050 13800) $PN C
R 1
J 0
(9040 13760);
DISPLAY 0.808511 (9040 13760);
FORCEPROP 1 LAST MATERIAL IC
J 0
(9100 13575);
DISPLAY 0.723404 (9100 13575);
PAINT GREEN (9100 13575);
FORCEPROP 2 LAST VALUE B340A-13-F
J 0
(9100 13650);
DISPLAY 0.638298 (9100 13650);
FORCEPROP 1 LAST NEEDS_NO_SIZE TRUE
R 1
J 0
(9100 13750);
DISPLAY 0.468085 (9100 13750);
PAINT GREEN (9100 13750);
DISPLAY INVISIBLE (9100 13750);
FORCEPROP 0 LAST PART_TYPE SMLF
J 0
(9100 13850);
DISPLAY 1.021277 (9100 13850);
DISPLAY INVISIBLE (9100 13850);
FORCEPROP 2 LAST CDS_LIB pure_quanta
R 1
J 0
(9050 13675);
DISPLAY INVISIBLE (9050 13675);
FORCEPROP 1 LAST CDS_LMAN_SYM_OUTLINE -75,50,75,-50
R 1
J 0
(9050 13675);
DISPLAY 0.468085 (9050 13675);
PAINT GREEN (9050 13675);
DISPLAY INVISIBLE (9050 13675);
FORCEPROP 1 LAST PATH I97
R 1
J 0
(9050 13675);
DISPLAY 0.723404 (9050 13675);
PAINT GREEN (9050 13675);
DISPLAY INVISIBLE (9050 13675);
FORCEPROP 1 LAST PART_NUMBER BC000340Z30
J 0
(9100 13600);
DISPLAY 0.595745 (9100 13600);
PAINT GREEN (9100 13600);
DISPLAY INVISIBLE (9100 13600);
FORCEADD GND..1
(9575 12800);
FORCEPROP 3 LASTPIN (9575 12850) SIG_NAME GND\g
J 0
(9585 12860);
DISPLAY 0.659574 (9585 12860);
PAINT MONO (9585 12860);
DISPLAY INVISIBLE (9585 12860);
FORCEPROP 2 LAST CDS_LIB pure_quanta_power
J 0
(9575 12800);
DISPLAY INVISIBLE (9575 12800);
FORCEPROP 1 LAST SIZE 1B
J 0
(9650 12750);
DISPLAY 0.872340 (9650 12750);
PAINT GREEN (9650 12750);
DISPLAY INVISIBLE (9650 12750);
FORCEPROP 1 LAST HDL_POWER GND
J 0
(9575 12950);
DISPLAY 0.872340 (9575 12950);
PAINT GREEN (9575 12950);
DISPLAY INVISIBLE (9575 12950);
FORCEPROP 1 LAST PATH I99
J 0
(9650 12800);
DISPLAY 0.872340 (9650 12800);
PAINT AQUA (9650 12800);
DISPLAY INVISIBLE (9650 12800);
FORCEADD DNS..2
(10325 13050);
PAINT RED (10325 13050);
FORCEPROP 2 LAST CDS_LIB mstr_misc
J 0
(10325 13050);
DISPLAY INVISIBLE (10325 13050);
FORCEPROP 1 LAST COMMENT_BODY TRUE
R 1
J 0
(10400 12825);
DISPLAY 0.872340 (10400 12825);
PAINT GREEN (10400 12825);
DISPLAY INVISIBLE (10400 12825);
FORCEADD CAD_NOTE..1
(9175 10050);
FORCEPROP 0 LAST S1 R3869/R3870 CO-LAYOUT
J 0
(9050 9925);
DISPLAY 0.808511 (9050 9925);
PAINT WHITE (9050 9925);
FORCEPROP 2 LAST CDS_LIB pure_quanta_power
J 0
(9175 10050);
DISPLAY INVISIBLE (9175 10050);
FORCEPROP 1 LAST COMMENT_BODY TRUE
J 0
(9200 10150);
DISPLAY 0.978723 (9200 10150);
DISPLAY INVISIBLE (9200 10150);
FORCEADD DNS..2
(8700 13100);
PAINT RED (8700 13100);
FORCEPROP 2 LAST CDS_LIB mstr_misc
J 0
(8700 13100);
DISPLAY INVISIBLE (8700 13100);
FORCEPROP 1 LAST COMMENT_BODY TRUE
R 1
J 0
(8775 12875);
DISPLAY 0.872340 (8775 12875);
PAINT GREEN (8775 12875);
DISPLAY INVISIBLE (8775 12875);
FORCEADD DNS..2
(3275 11850);
PAINT RED (3275 11850);
FORCEPROP 2 LAST CDS_LIB mstr_misc
J 0
(3275 11850);
DISPLAY INVISIBLE (3275 11850);
FORCEPROP 1 LAST COMMENT_BODY TRUE
R 1
J 0
(3350 11625);
DISPLAY 0.872340 (3350 11625);
PAINT GREEN (3350 11625);
DISPLAY INVISIBLE (3350 11625);
FORCEADD DNS..2
(3325 12200);
PAINT RED (3325 12200);
FORCEPROP 2 LAST CDS_LIB mstr_misc
J 0
(3325 12200);
DISPLAY INVISIBLE (3325 12200);
FORCEPROP 1 LAST COMMENT_BODY TRUE
R 1
J 0
(3400 11975);
DISPLAY 0.872340 (3400 11975);
PAINT GREEN (3400 11975);
DISPLAY INVISIBLE (3400 11975);
FORCEADD DNS..2
(2950 9900);
PAINT RED (2950 9900);
FORCEPROP 2 LAST CDS_LIB mstr_misc
J 0
(2950 9900);
DISPLAY INVISIBLE (2950 9900);
FORCEPROP 1 LAST COMMENT_BODY TRUE
R 1
J 0
(3025 9675);
DISPLAY 0.872340 (3025 9675);
PAINT GREEN (3025 9675);
DISPLAY INVISIBLE (3025 9675);
FORCEADD DNS..2
(2600 10200);
PAINT RED (2600 10200);
FORCEPROP 2 LAST CDS_LIB mstr_misc
J 0
(2600 10200);
DISPLAY INVISIBLE (2600 10200);
FORCEPROP 1 LAST COMMENT_BODY TRUE
R 1
J 0
(2675 9975);
DISPLAY 0.872340 (2675 9975);
PAINT GREEN (2675 9975);
DISPLAY INVISIBLE (2675 9975);
FORCEADD DNS..2
(8425 11050);
PAINT RED (8425 11050);
FORCEPROP 2 LAST CDS_LIB mstr_misc
J 0
(8425 11050);
DISPLAY INVISIBLE (8425 11050);
FORCEPROP 1 LAST COMMENT_BODY TRUE
R 1
J 0
(8500 10825);
DISPLAY 0.872340 (8500 10825);
PAINT GREEN (8500 10825);
DISPLAY INVISIBLE (8500 10825);
FORCEADD QUANTA_TITLE_BLOCK_C..1
(10975 7800);
FORCEPROP 0 LAST CDS_CON_LAST_MODIFIED Thu Sep 14 16:12:38 2023
J 0
(9090 7815);
PAINT MONO (9090 7815);
DISPLAY INVISIBLE (9090 7815);
FORCEPROP 2 LAST CUSTOM_TXT_CDS <XR_PAGE_TITLE>
J 0
(3085 13050);
DISPLAY 0.638298 (3085 13050);
PAINT PINK (3085 13050);
DISPLAY INVISIBLE (3085 13050);
FORCEPROP 2 LAST CUSTOM_TXT_CDS <CON_LAST_MODIFIED>
J 0
(9090 7815);
DISPLAY 0.978723 (9090 7815);
FORCEPROP 2 LAST CUSTOM_TXT_CDS <Q_NUMBER>
J 0
(9572 7903);
DISPLAY 1.212766 (9572 7903);
FORCEPROP 2 LAST CUSTOM_TXT_CDS <Q_PROJ>
J 0
(8593 7902);
DISPLAY 1.212766 (8593 7902);
FORCEPROP 2 LAST CUSTOM_TXT_CDS <Q_REV>
J 0
(10791 7903);
DISPLAY 1.212766 (10791 7903);
FORCEPROP 2 LAST CUSTOM_TXT_CDS <NAME_1>
J 0
(7800 7975);
FORCEPROP 2 LAST CUSTOM_TXT_CDS <NAME_2>
J 0
(7800 7850);
FORCEPROP 2 LAST CUSTOM_TXT_CDS <CON_PAGE_NUM> OF <CON_TOTAL_PAGES>
J 0
(10529 7818);
DISPLAY 0.978723 (10529 7818);
FORCEPROP 1 LAST Q_TITLE SFF_OCP3.0 HSC(1/3)
J 0
(1725 7875);
DISPLAY 2.446809 (1725 7875);
PAINT GREEN (1725 7875);
FORCEPROP 2 LAST PAGE_BORDER TRUE
J 0
(3085 13050);
DISPLAY 0.638298 (3085 13050);
PAINT PINK (3085 13050);
DISPLAY INVISIBLE (3085 13050);
FORCEPROP 1 LAST CDS_LMAN_SYM_OUTLINE -9475,6775,100,-125
J 0
(10975 7800);
DISPLAY 0.468085 (10975 7800);
PAINT GREEN (10975 7800);
DISPLAY INVISIBLE (10975 7800);
FORCEPROP 2 LAST CDS_LIB pure_quanta
J 0
(10975 7800);
PAINT MONO (10975 7800);
DISPLAY INVISIBLE (10975 7800);
FORCEPROP 2 LAST CDS_XR_PAGE_TITLE CR-134 : @T6G_MB_LIB.T6G(SCH_1):PAGE134
J 0
(3085 13050);
DISPLAY 0.638298 (3085 13050);
PAINT PINK (3085 13050);
DISPLAY INVISIBLE (3085 13050);
FORCEPROP 1 LAST Q_DEPT BU9
J 1
(7212 7849);
DISPLAY 1.957447 (7212 7849);
PAINT GREEN (7212 7849);
DISPLAY INVISIBLE (7212 7849);
FORCEPROP 1 LAST COMMENT_BODY TRUE
J 0
(10987 7787);
DISPLAY 0.978723 (10987 7787);
PAINT GREEN (10987 7787);
DISPLAY INVISIBLE (10987 7787);
FORCEADD DNS..2
(3625 11500);
PAINT RED (3625 11500);
FORCEPROP 2 LAST CDS_LIB mstr_misc
J 0
(3625 11500);
DISPLAY INVISIBLE (3625 11500);
FORCEPROP 1 LAST COMMENT_BODY TRUE
R 1
J 0
(3700 11275);
DISPLAY 0.872340 (3700 11275);
PAINT GREEN (3700 11275);
DISPLAY INVISIBLE (3700 11275);
FORCEADD DNS..2
(9400 10525);
PAINT RED (9400 10525);
FORCEPROP 2 LAST CDS_LIB mstr_misc
J 0
(9400 10525);
DISPLAY INVISIBLE (9400 10525);
FORCEPROP 1 LAST COMMENT_BODY TRUE
R 1
J 0
(9475 10300);
DISPLAY 0.553191 (9475 10300);
PAINT GREEN (9475 10300);
DISPLAY INVISIBLE (9475 10300);
FORCEADD DNS..2
(9350 12750);
PAINT RED (9350 12750);
FORCEPROP 2 LAST CDS_LIB mstr_misc
J 0
(9350 12750);
DISPLAY INVISIBLE (9350 12750);
FORCEPROP 1 LAST COMMENT_BODY TRUE
R 1
J 0
(9425 12525);
DISPLAY 0.872340 (9425 12525);
PAINT GREEN (9425 12525);
DISPLAY INVISIBLE (9425 12525);
WIRE 16 -1 (5950 8225)(5950 8275);
WIRE 16 -1 (5900 13400)(5900 13275);
WIRE 16 -1 (3625 10075)(3625 9975);
WIRE 16 -1 (3475 11075)(3475 10900);
WIRE 16 -1 (3650 11400)(3650 11300);
WIRE 16 -1 (5950 9125)(5950 9175);
WIRE 16 -1 (6025 10100)(6025 10000);
WIRE 16 -1 (4475 10375)(4475 10325);
WIRE 16 -1 (4225 11675)(4225 11575);
WIRE 16 -1 (4975 12050)(4975 11950);
WIRE 16 -1 (3025 9800)(3025 9700);
WIRE 16 -1 (6250 12150)(6250 12050);
WIRE 16 -1 (4225 12675)(4225 12575);
WIRE 16 -1 (6575 12975)(6575 12775);
WIRE 16 -1 (6575 12775)(6700 12775);
WIRE 16 -1 (6575 12775)(6575 12750);
WIRE 16 -1 (9175 10825)(9200 10825);
WIRE 16 -1 (9200 10825)(9200 10800);
WIRE 16 -1 (9375 12875)(9575 12875);
WIRE 16 -1 (9575 12875)(9575 12850);
WIRE 16 -1 (3900 9500)(3950 9500);
WIRE 16 -1 (4950 9500)(3950 9500);
FORCEPROP 0 LAST CDS_PHYS_NET_NAME OCP_SFF_PRSNT0_R_N
J 0
(4840 9542);
PAINT MONO (4840 9542);
DISPLAY INVISIBLE (4840 9542);
FORCEPROP 2 LAST SIG_NAME OCP_SFF_PRSNT0_R_N
J 0
(4340 9510);
DISPLAY 0.553191 (4340 9510);
PAINT WHITE (4340 9510);
WIRE 16 -1 (3950 9650)(3950 9500);
WIRE 16 -1 (4225 9650)(4225 9400);
WIRE 16 -1 (4950 9400)(4225 9400);
FORCEPROP 0 LAST CDS_PHYS_NET_NAME OCP_SFF_PRSNT1_R_N
J 0
(4840 9442);
PAINT MONO (4840 9442);
DISPLAY INVISIBLE (4840 9442);
FORCEPROP 2 LAST SIG_NAME OCP_SFF_PRSNT1_R_N
J 0
(4340 9410);
DISPLAY 0.553191 (4340 9410);
PAINT WHITE (4340 9410);
WIRE 16 -1 (3900 9400)(4225 9400);
WIRE 16 -1 (3900 8950)(3900 9075);
WIRE 16 -1 (4125 9075)(3900 9075);
WIRE 16 -1 (3900 9100)(3900 9075);
WIRE 16 -1 (4125 8950)(4125 9075);
WIRE 16 -1 (5300 11300)(5300 11185);
WIRE 16 -1 (5300 11185)(5450 11185);
WIRE 16 -1 (5675 11185)(5450 11185);
WIRE 16 -1 (5450 11125)(5450 11185);
WIRE 16 -1 (5675 11185)(5675 11350);
WIRE 16 2175 (1725 14375)(3428 14375);
WIRE 16 2175 (1725 14375)(1725 13475);
WIRE 16 2175 (3428 14375)(3428 13475);
WIRE 16 2175 (1725 13475)(3428 13475);
WIRE 16 -1 (8925 10400)(9275 10400);
WIRE 16 -1 (8925 10525)(8925 10400);
WIRE 16 -1 (9275 10525)(8925 10525);
WIRE 16 -1 (8475 10525)(8925 10525);
WIRE 16 -1 (8475 10425)(8475 10525);
FORCEPROP 2 LAST SIG_NAME P12V_OCP_SENSE_1
J 0
(8090 10535);
DISPLAY 0.574468 (8090 10535);
FORCEPROP 2 LASTPROP $XRERR UNIQUE?
J 0
(7850 10535);
DISPLAY 0.638298 (7850 10535);
PAINT MONO (7850 10535);
DISPLAY INVISIBLE (7850 10535);
WIRE 16 -1 (8025 10525)(8475 10525);
WIRE 16 -1 (8975 10825)(8725 10825);
WIRE 16 -1 (8725 10950)(8725 10825);
WIRE 16 -1 (8725 10825)(8400 10825);
WIRE 16 -1 (8400 10950)(8400 10825);
WIRE 16 -1 (8400 10825)(8025 10825);
FORCEPROP 2 LAST SIG_NAME P12V_OCP_GATE_1
J 0
(8090 10835);
DISPLAY 0.574468 (8090 10835);
FORCEPROP 2 LASTPROP $XRERR UNIQUE?
J 0
(7850 10835);
DISPLAY 0.638298 (7850 10835);
PAINT MONO (7850 10835);
DISPLAY INVISIBLE (7850 10835);
WIRE 16 -1 (8825 11575)(8825 11500);
WIRE 16 -1 (8825 11500)(9300 11500);
WIRE 16 -1 (9725 11500)(9300 11500);
WIRE 16 -1 (9300 11500)(9300 11575);
WIRE 16 -1 (10125 11500)(9725 11500);
WIRE 16 -1 (9725 11500)(9725 11575);
WIRE 16 -1 (10125 11500)(10125 11575);
WIRE 16 -1 (10125 11375)(10125 11500);
WIRE 16 -1 (5300 11600)(5300 11675);
WIRE 16 -1 (5300 11675)(5450 11675);
WIRE 16 -1 (5675 11675)(5450 11675);
WIRE 16 -1 (5450 11750)(5450 11675);
WIRE 16 -1 (5675 11675)(6025 11675);
WIRE 16 -1 (5675 11675)(5675 11550);
WIRE 16 -1 (6025 11675)(6350 11675);
WIRE 16 -1 (6025 11675)(6025 11250);
WIRE 16 -1 (7125 11675)(6350 11675);
WIRE 16 -1 (6350 11675)(6350 11550);
WIRE 16 -1 (7125 11675)(7125 11225);
WIRE 16 -1 (7125 11225)(7225 11225);
WIRE 16 -1 (7125 11225)(7125 11175);
WIRE 16 -1 (7125 11175)(7225 11175);
WIRE 16 -1 (7125 11175)(7125 11125);
WIRE 16 -1 (7125 11125)(7225 11125);
WIRE 16 -1 (7125 11125)(7125 11075);
WIRE 16 -1 (7125 11075)(7225 11075);
WIRE 16 -1 (7125 11075)(7125 11025);
WIRE 16 -1 (7125 11025)(7225 11025);
WIRE 16 -1 (7125 11025)(7125 10975);
WIRE 16 -1 (7125 10975)(7225 10975);
WIRE 16 -1 (7125 10975)(7125 10925);
WIRE 16 -1 (7125 10925)(7225 10925);
WIRE 16 -1 (6700 10825)(7225 10825);
FORCEPROP 2 LAST SIG_NAME P12V_OCP_VCC_1
J 0
(6765 10835);
DISPLAY 0.574468 (6765 10835);
FORCEPROP 2 LASTPROP $XRERR UNIQUE?
J 0
(6525 10835);
DISPLAY 0.638298 (6525 10835);
PAINT MONO (6525 10835);
DISPLAY INVISIBLE (6525 10835);
WIRE 16 -1 (6700 11250)(6700 10825);
WIRE 16 -1 (6700 11250)(6350 11250);
WIRE 16 -1 (6350 11350)(6350 11250);
WIRE 16 -1 (6350 11250)(6350 11125);
WIRE 16 -1 (6325 10525)(7225 10525);
FORCEPROP 2 LAST SIG_NAME P12V_OCP_OV_1
J 0
(6790 10535);
DISPLAY 0.574468 (6790 10535);
FORCEPROP 2 LASTPROP $XRERR UNIQUE?
J 0
(6550 10535);
DISPLAY 0.638298 (6550 10535);
PAINT MONO (6550 10535);
DISPLAY INVISIBLE (6550 10535);
WIRE 16 -1 (6325 10325)(6325 10525);
WIRE 16 -1 (6025 10325)(6325 10325);
WIRE 16 -1 (6025 10375)(6025 10325);
WIRE 16 -1 (6025 10325)(6025 10300);
WIRE 16 -1 (3650 11600)(3650 11825);
WIRE 16 -1 (3650 11825)(3975 11825);
WIRE 16 -1 (3550 11825)(3650 11825);
FORCEPROP 2 LAST SIG_NAME P3V3_OCP_EN_1_R
J 0
(3565 11835);
DISPLAY 0.595745 (3565 11835);
FORCEPROP 2 LASTPROP $XRERR UNIQUE?
J 0
(3325 11835);
DISPLAY 0.638298 (3325 11835);
PAINT MONO (3325 11835);
DISPLAY INVISIBLE (3325 11835);
WIRE 16 -1 (3550 12225)(3550 11825);
WIRE 16 -1 (3375 11825)(3550 11825);
WIRE 16 -1 (3550 12650)(3550 12225);
WIRE 16 -1 (3425 12225)(3550 12225);
WIRE 16 -1 (3375 12650)(3550 12650);
WIRE 16 -1 (8700 12325)(8700 12225);
WIRE 16 -1 (8575 12225)(8700 12225);
WIRE 16 -1 (8475 12225)(8575 12225);
WIRE 16 -1 (8575 12150)(8575 12225);
WIRE 16 -1 (8475 12475)(8475 12225);
WIRE 16 -1 (8475 12225)(8425 12225);
WIRE 16 -1 (8425 12375)(8425 12225);
WIRE 16 -1 (8375 12225)(8425 12225);
WIRE 16 -1 (8250 12475)(8475 12475);
WIRE 16 -1 (8375 12325)(8375 12225);
WIRE 16 -1 (8325 12225)(8375 12225);
WIRE 16 -1 (8250 12375)(8425 12375);
WIRE 16 -1 (8325 12225)(8325 12275);
WIRE 16 -1 (8250 12325)(8375 12325);
WIRE 16 -1 (8325 12275)(8250 12275);
WIRE 16 -1 (8250 12575)(8700 12575);
WIRE 16 -1 (8700 12525)(8700 12575);
FORCEPROP 2 LAST SIG_NAME P3V3_OCP_SENSE_1
J 0
(8315 12585);
DISPLAY 0.574468 (8315 12585);
FORCEPROP 2 LASTPROP $XRERR UNIQUE?
J 0
(8075 12585);
DISPLAY 0.638298 (8075 12585);
PAINT MONO (8075 12585);
DISPLAY INVISIBLE (8075 12585);
WIRE 16 -1 (9900 11225)(9650 11225);
WIRE 16 -1 (9900 11225)(9900 11100);
WIRE 16 -1 (9650 11250)(9650 11225);
WIRE 16 -1 (9650 11225)(9475 11225);
WIRE 16 -1 (9475 11225)(9475 11100);
WIRE 16 -1 (6025 10625)(7225 10625);
FORCEPROP 2 LAST SIG_NAME P12V_OCP_UV_1
J 0
(6790 10635);
DISPLAY 0.574468 (6790 10635);
FORCEPROP 2 LASTPROP $XRERR UNIQUE?
J 0
(6550 10635);
DISPLAY 0.638298 (6550 10635);
PAINT MONO (6550 10635);
DISPLAY INVISIBLE (6550 10635);
WIRE 16 -1 (6025 10625)(6025 10825);
WIRE 16 -1 (6025 10625)(6025 10575);
WIRE 16 -1 (6025 11050)(6025 10825);
WIRE 16 -1 (5600 10825)(6025 10825);
WIRE 16 -1 (8475 10225)(8475 10175);
WIRE 16 -1 (8350 10175)(8475 10175);
WIRE 16 -1 (8350 10100)(8350 10175);
WIRE 16 -1 (8250 10175)(8350 10175);
WIRE 16 -1 (8250 10425)(8250 10175);
WIRE 16 -1 (8250 10175)(8200 10175);
WIRE 16 -1 (8200 10325)(8200 10175);
WIRE 16 -1 (8150 10175)(8200 10175);
WIRE 16 -1 (8025 10425)(8250 10425);
WIRE 16 -1 (8150 10275)(8150 10175);
WIRE 16 -1 (8100 10175)(8150 10175);
WIRE 16 -1 (8025 10325)(8200 10325);
WIRE 16 -1 (8100 10175)(8100 10225);
WIRE 16 -1 (8025 10275)(8150 10275);
WIRE 16 -1 (8100 10225)(8025 10225);
WIRE 16 -1 (5900 13725)(6250 13725);
WIRE 16 -1 (5900 13725)(5900 13600);
WIRE 16 -1 (5900 13800)(5900 13725);
WIRE 16 -1 (6250 13725)(6575 13725);
WIRE 16 -1 (6250 13725)(6250 13350);
WIRE 16 -1 (7350 13725)(6575 13725);
WIRE 16 -1 (6575 13725)(6575 13600);
WIRE 16 -1 (7350 13725)(7350 13275);
WIRE 16 -1 (7350 13275)(7450 13275);
WIRE 16 -1 (7350 13275)(7350 13225);
WIRE 16 -1 (7350 13225)(7450 13225);
WIRE 16 -1 (7350 13225)(7350 13175);
WIRE 16 -1 (7350 13175)(7450 13175);
WIRE 16 -1 (7350 13175)(7350 13125);
WIRE 16 -1 (7350 13125)(7450 13125);
WIRE 16 -1 (7350 13125)(7350 13075);
WIRE 16 -1 (7350 13075)(7450 13075);
WIRE 16 -1 (7350 13075)(7350 13025);
WIRE 16 -1 (7350 13025)(7450 13025);
WIRE 16 -1 (7350 13025)(7350 12975);
WIRE 16 -1 (7350 12975)(7450 12975);
WIRE 16 -1 (6350 10925)(6350 10725);
WIRE 16 -1 (6350 10725)(6475 10725);
WIRE 16 -1 (6250 10725)(6350 10725);
WIRE 16 -1 (6250 10725)(6250 10700);
WIRE 16 -1 (8200 9425)(8200 9525);
WIRE 16 -1 (8200 9525)(8350 9525);
WIRE 16 -1 (8350 9425)(8350 9525);
WIRE 16 -1 (8350 9525)(8350 9550);
WIRE 16 -1 (7200 10325)(7200 10025);
WIRE 16 -1 (7225 10325)(7200 10325);
WIRE 16 -1 (7200 10025)(6875 10025);
WIRE 16 -1 (6875 10025)(6875 10125);
WIRE 16 -1 (6875 9975)(6875 10025);
WIRE 16 -1 (5950 9375)(5950 9450);
WIRE 16 -1 (5950 9500)(5950 9450);
WIRE 16 -1 (5950 9450)(5600 9450);
WIRE 16 -1 (5950 8475)(5950 8550);
WIRE 16 -1 (5950 8600)(5950 8550);
WIRE 16 -1 (5950 8550)(5600 8550);
WIRE 16 -1 (4875 9450)(4950 9450);
WIRE 16 -1 (4875 9225)(4875 9450);
WIRE 16 -1 (4875 8550)(4950 8550);
WIRE 16 -1 (4875 8300)(4875 8550);
WIRE 16 -1 (10125 13750)(10125 13850);
WIRE 16 -1 (10125 13900)(10125 13850);
WIRE 16 -1 (10125 13850)(9550 13850);
WIRE 16 -1 (9550 13750)(9550 13850);
WIRE 16 -1 (9050 13850)(9550 13850);
WIRE 16 -1 (8770 13850)(9050 13850);
WIRE 16 -1 (9050 13850)(9050 13800);
WIRE 16 -1 (8770 13850)(8770 13275);
WIRE 16 -1 (8770 13275)(8925 13275);
WIRE 16 -1 (8675 13275)(8770 13275);
WIRE 16 -1 (8675 13200)(8675 13275);
WIRE 16 -1 (8557 13275)(8675 13275);
WIRE 16 -1 (8925 13275)(8925 13200);
WIRE 16 -1 (8557 13225)(8557 13275);
WIRE 16 -1 (8250 13275)(8557 13275);
WIRE 16 -1 (8557 13175)(8557 13225);
WIRE 16 -1 (8250 13225)(8557 13225);
WIRE 16 -1 (8557 13125)(8557 13175);
WIRE 16 -1 (8250 13175)(8557 13175);
WIRE 16 -1 (8557 13075)(8557 13125);
WIRE 16 -1 (8250 13125)(8557 13125);
WIRE 16 -1 (8557 13025)(8557 13075);
WIRE 16 -1 (8557 13075)(8250 13075);
WIRE 16 -1 (8557 12975)(8557 13025);
WIRE 16 -1 (8250 13025)(8557 13025);
WIRE 16 -1 (8250 12975)(8557 12975);
WIRE 16 -1 (10125 13475)(10125 13550);
WIRE 16 -1 (10125 13400)(10125 13475);
WIRE 16 -1 (10125 13475)(9550 13475);
WIRE 16 -1 (9550 13475)(9550 13550);
WIRE 16 -1 (9050 13475)(9550 13475);
WIRE 16 -1 (9050 13550)(9050 13475);
WIRE 16 -1 (10225 13250)(9875 13250);
WIRE 16 -1 (10225 13250)(10225 13150);
WIRE 16 -1 (9875 13275)(9875 13250);
WIRE 16 -1 (9875 13250)(9675 13250);
WIRE 16 -1 (9675 13250)(9675 13150);
WIRE 16 -1 (6900 12775)(7450 12775);
FORCEPROP 2 LAST SIG_NAME P3V3_OCP_REG_1
J 0
(6990 12785);
DISPLAY 0.574468 (6990 12785);
FORCEPROP 2 LASTPROP $XRERR UNIQUE?
J 0
(6750 12785);
DISPLAY 0.638298 (6750 12785);
PAINT MONO (6750 12785);
DISPLAY INVISIBLE (6750 12785);
WIRE 16 -1 (6925 12875)(7450 12875);
FORCEPROP 2 LAST SIG_NAME P3V3_OCP_VCC_1
J 0
(6990 12885);
DISPLAY 0.574468 (6990 12885);
FORCEPROP 2 LASTPROP $XRERR UNIQUE?
J 0
(6750 12885);
DISPLAY 0.638298 (6750 12885);
PAINT MONO (6750 12885);
DISPLAY INVISIBLE (6750 12885);
WIRE 16 -1 (6925 13300)(6925 12875);
WIRE 16 -1 (6925 13300)(6575 13300);
WIRE 16 -1 (6575 13400)(6575 13300);
WIRE 16 -1 (6575 13300)(6575 13175);
WIRE 16 -1 (2500 10225)(1925 10225);
FORCEPROP 2 LAST SIG_NAME P12V_OCP_SFF_EN_R
J 0
(1915 10235);
DISPLAY 0.489362 (1915 10235);
WIRE 16 -1 (5400 10825)(4475 10825);
FORCEPROP 2 LAST SIG_NAME P12V_OCP_UV_1_R
J 0
(4790 10835);
DISPLAY 0.574468 (4790 10835);
FORCEPROP 2 LASTPROP $XRERR UNIQUE?
J 0
(4550 10835);
DISPLAY 0.638298 (4550 10835);
PAINT MONO (4550 10835);
DISPLAY INVISIBLE (4550 10835);
WIRE 16 -1 (4475 10775)(4475 10825);
WIRE 16 -1 (3475 10700)(3475 10525);
WIRE 16 -1 (3475 10525)(3625 10525);
FORCEPROP 2 LAST SIG_NAME P12V_OCP_1_EN_G
J 0
(3515 10535);
DISPLAY 0.595745 (3515 10535);
FORCEPROP 2 LASTPROP $XRERR UNIQUE?
J 0
(3275 10535);
DISPLAY 0.638298 (3275 10535);
PAINT MONO (3275 10535);
DISPLAY INVISIBLE (3275 10535);
WIRE 16 -1 (3625 10525)(4225 10525);
WIRE 16 -1 (3625 10475)(3625 10525);
WIRE 16 -1 (9175 12875)(8925 12875);
WIRE 16 -1 (8925 13000)(8925 12875);
WIRE 16 -1 (8925 12875)(8675 12875);
WIRE 16 -1 (8675 13000)(8675 12875);
WIRE 16 -1 (8675 12875)(8250 12875);
FORCEPROP 2 LAST SIG_NAME P3V3_OCP_GATE_PU202_1
J 0
(8315 12885);
DISPLAY 0.574468 (8315 12885);
FORCEPROP 2 LASTPROP $XRERR UNIQUE?
J 0
(8075 12885);
DISPLAY 0.638298 (8075 12885);
PAINT MONO (8075 12885);
DISPLAY INVISIBLE (8075 12885);
WIRE 16 -1 (6550 12575)(7450 12575);
FORCEPROP 2 LAST SIG_NAME P3V3_OCP_OV_1
J 0
(7015 12585);
DISPLAY 0.574468 (7015 12585);
FORCEPROP 2 LASTPROP $XRERR UNIQUE?
J 0
(6775 12585);
DISPLAY 0.638298 (6775 12585);
PAINT MONO (6775 12585);
DISPLAY INVISIBLE (6775 12585);
WIRE 16 -1 (6550 12375)(6550 12575);
WIRE 16 -1 (6250 12375)(6550 12375);
WIRE 16 -1 (6250 12425)(6250 12375);
WIRE 16 -1 (6250 12375)(6250 12350);
WIRE 16 -1 (7450 12475)(7100 12475);
FORCEPROP 2 LAST SIG_NAME P3V3_OCP_CB_1
J 0
(7015 12485);
DISPLAY 0.574468 (7015 12485);
FORCEPROP 2 LASTPROP $XRERR UNIQUE?
J 0
(6775 12485);
DISPLAY 0.638298 (6775 12485);
PAINT MONO (6775 12485);
DISPLAY INVISIBLE (6775 12485);
WIRE 16 -1 (7100 12475)(7100 12375);
WIRE 16 -1 (6950 8900)(8350 8900);
FORCEPROP 0 LAST CDS_PHYS_NET_NAME HP_LVC3_OCP_V3_1_PRSNT2_N
J 0
(8315 8942);
PAINT MONO (8315 8942);
DISPLAY INVISIBLE (8315 8942);
FORCEPROP 2 LAST SIG_NAME HP_LVC3_OCP_SFF_PRSNT2_PLD_N
J 0
(7265 8910);
DISPLAY 0.553191 (7265 8910);
PAINT WHITE (7265 8910);
WIRE 16 -1 (8350 9225)(8350 8900);
WIRE 16 -1 (8350 8900)(8425 8900);
WIRE 16 -1 (5600 9500)(5725 9500);
WIRE 16 -1 (5725 9500)(5725 9400);
WIRE 16 -1 (5725 9400)(5600 9400);
WIRE 16 -1 (5725 9400)(5725 8900);
WIRE 16 -1 (6525 8900)(5725 8900);
FORCEPROP 2 LAST SIG_NAME HP_LVC3_OCP_V3_1_PRSNT2_N_R
J 0
(5790 8910);
DISPLAY 0.553191 (5790 8910);
PAINT WHITE (5790 8910);
FORCEPROP 2 LASTPROP $XRERR UNIQUE?
J 0
(5550 8910);
DISPLAY 0.638298 (5550 8910);
PAINT MONO (5550 8910);
DISPLAY INVISIBLE (5550 8910);
WIRE 16 -1 (5725 8600)(5725 8900);
WIRE 16 -1 (5725 8600)(5725 8500);
WIRE 16 -1 (5725 8600)(5600 8600);
WIRE 16 -1 (6750 8900)(6525 8900);
FORCEPROP 0 LAST CDS_PHYS_NET_NAME HP_LVC3_OCP_V3_1_PRSNT2_N_R
J 0
(6640 8942);
PAINT MONO (6640 8942);
DISPLAY INVISIBLE (6640 8942);
WIRE 16 -1 (6525 8900)(6525 8675);
WIRE 16 -1 (6525 8675)(6750 8675);
WIRE 16 -1 (5725 8500)(5600 8500);
WIRE 16 -1 (6950 8675)(8200 8675);
FORCEPROP 2 LAST SIG_NAME HP_LVC3_OCP_SFF_PRSNT2_N
J 0
(7265 8685);
DISPLAY 0.680851 (7265 8685);
WIRE 16 -1 (8200 9225)(8200 8675);
WIRE 16 -1 (8200 8675)(8425 8675);
WIRE 16 -1 (4950 8600)(3900 8600);
FORCEPROP 0 LAST CDS_PHYS_NET_NAME OCP_SFF_PRSNT2_R_N
J 0
(4840 8642);
PAINT MONO (4840 8642);
DISPLAY INVISIBLE (4840 8642);
FORCEPROP 2 LAST SIG_NAME OCP_SFF_PRSNT2_R_N
J 0
(4340 8610);
DISPLAY 0.553191 (4340 8610);
PAINT WHITE (4340 8610);
WIRE 16 -1 (3900 8750)(3900 8600);
WIRE 16 -1 (3900 8600)(3775 8600);
WIRE 16 -1 (4950 8500)(4125 8500);
FORCEPROP 0 LAST CDS_PHYS_NET_NAME OCP_SFF_PRSNT3_R_N
J 0
(4840 8542);
PAINT MONO (4840 8542);
DISPLAY INVISIBLE (4840 8542);
FORCEPROP 2 LAST SIG_NAME OCP_SFF_PRSNT3_R_N
J 0
(4340 8510);
DISPLAY 0.553191 (4340 8510);
PAINT WHITE (4340 8510);
WIRE 16 -1 (4125 8750)(4125 8500);
WIRE 16 -1 (4125 8500)(3775 8500);
WIRE 16 -1 (6250 12675)(7450 12675);
FORCEPROP 2 LAST SIG_NAME P3V3_OCP_UV_1
J 0
(7015 12685);
DISPLAY 0.574468 (7015 12685);
FORCEPROP 2 LASTPROP $XRERR UNIQUE?
J 0
(6775 12685);
DISPLAY 0.638298 (6775 12685);
PAINT MONO (6775 12685);
DISPLAY INVISIBLE (6775 12685);
WIRE 16 -1 (6250 12675)(6250 12875);
WIRE 16 -1 (6250 12675)(6250 12625);
WIRE 16 -1 (6250 13150)(6250 12875);
WIRE 16 -1 (5750 12875)(6250 12875);
WIRE 16 -1 (6675 10725)(7225 10725);
FORCEPROP 2 LAST SIG_NAME P12V_OCP_REG_1
J 0
(6765 10735);
DISPLAY 0.574468 (6765 10735);
FORCEPROP 2 LASTPROP $XRERR UNIQUE?
J 0
(6525 10735);
DISPLAY 0.638298 (6525 10735);
PAINT MONO (6525 10735);
DISPLAY INVISIBLE (6525 10735);
WIRE 16 -1 (3950 9850)(3950 9975);
WIRE 16 -1 (3950 9975)(4150 9975);
WIRE 16 -1 (4150 10000)(4150 9975);
WIRE 16 -1 (4225 9975)(4150 9975);
WIRE 16 -1 (4225 9850)(4225 9975);
WIRE 16 -1 (4225 12375)(4225 12200);
WIRE 16 -1 (4225 12200)(4725 12200);
FORCEPROP 2 LAST SIG_NAME P3V3_OCP_1_EN_G
J 0
(4265 12210);
DISPLAY 0.595745 (4265 12210);
FORCEPROP 2 LASTPROP $XRERR UNIQUE?
J 0
(4025 12210);
DISPLAY 0.638298 (4025 12210);
PAINT MONO (4025 12210);
DISPLAY INVISIBLE (4025 12210);
WIRE 16 -1 (4225 12075)(4225 12200);
WIRE 16 -1 (2800 10650)(1900 10650);
FORCEPROP 2 LAST SIG_NAME P12V_OCP_SFF_BUF_EN_R
J 0
(1965 10660);
DISPLAY 0.680851 (1965 10660);
WIRE 16 -1 (3175 12650)(2125 12650);
FORCEPROP 2 LAST SIG_NAME P12V_OCP_SFF_BUF_EN_R
J 0
(2215 12660);
DISPLAY 0.680851 (2215 12660);
WIRE 16 -1 (8250 12775)(9225 12775);
FORCEPROP 2 LAST SIG_NAME P3V3_OCP_PWRGD_1
J 0
(8315 12785);
DISPLAY 0.574468 (8315 12785);
FORCEPROP 2 LASTPROP $XRERR UNIQUE?
J 0
(8075 12785);
DISPLAY 0.638298 (8075 12785);
PAINT MONO (8075 12785);
DISPLAY INVISIBLE (8075 12785);
WIRE 16 -1 (8250 12675)(9675 12675);
FORCEPROP 2 LAST SIG_NAME P3V3_OCP_FAULT_1
J 0
(8315 12685);
DISPLAY 0.574468 (8315 12685);
FORCEPROP 2 LASTPROP $XRERR UNIQUE?
J 0
(8075 12685);
DISPLAY 0.638298 (8075 12685);
PAINT MONO (8075 12685);
DISPLAY INVISIBLE (8075 12685);
WIRE 16 -1 (9675 12675)(9675 12950);
WIRE 16 -1 (3000 10650)(3325 10650);
WIRE 16 -1 (3325 10650)(3325 10225);
WIRE 16 -1 (3375 10225)(3325 10225);
WIRE 16 -1 (3325 10225)(3025 10225);
WIRE 16 -1 (3025 10000)(3025 10225);
WIRE 16 -1 (2700 10225)(3025 10225);
FORCEPROP 2 LAST SIG_NAME P12V_OCP_EN_1_R
J 0
(2865 10225);
DISPLAY 0.595745 (2865 10225);
FORCEPROP 2 LASTPROP $XRERR UNIQUE?
J 0
(2625 10225);
DISPLAY 0.638298 (2625 10225);
PAINT MONO (2625 10225);
DISPLAY INVISIBLE (2625 10225);
WIRE 16 -1 (8025 10725)(9025 10725);
FORCEPROP 2 LAST SIG_NAME P12V_OCP_PWRGD_1
J 0
(8090 10735);
DISPLAY 0.574468 (8090 10735);
FORCEPROP 2 LASTPROP $XRERR UNIQUE?
J 0
(7850 10735);
DISPLAY 0.638298 (7850 10735);
PAINT MONO (7850 10735);
DISPLAY INVISIBLE (7850 10735);
WIRE 16 -1 (9475 10525)(10575 10525);
FORCEPROP 2 LAST SIG_NAME P12V_OCP_SFF_ISENSE_MAM_MAM
J 0
(9715 10535);
DISPLAY 0.574468 (9715 10535);
WIRE 16 -1 (9475 10400)(10575 10400);
FORCEPROP 2 LAST SIG_NAME P12V_OCP_SFF_ISENSE_MAM_TIC
J 0
(9715 10410);
DISPLAY 0.574468 (9715 10410);
WIRE 16 -1 (7425 12375)(7425 12075);
WIRE 16 -1 (7450 12375)(7425 12375);
WIRE 16 -1 (7425 12075)(7100 12075);
WIRE 16 -1 (7100 12075)(7100 12175);
WIRE 16 -1 (7100 12025)(7100 12075);
WIRE 16 -1 (5550 12875)(4975 12875);
FORCEPROP 2 LAST SIG_NAME P3V3_OCP_UV_1_R1
J 0
(5090 12885);
DISPLAY 0.574468 (5090 12885);
FORCEPROP 2 LASTPROP $XRERR UNIQUE?
J 0
(4850 12885);
DISPLAY 0.638298 (4850 12885);
PAINT MONO (4850 12885);
DISPLAY INVISIBLE (4850 12885);
WIRE 16 -1 (4975 12450)(4975 12875);
WIRE 16 -1 (2175 11825)(3175 11825);
FORCEPROP 2 LAST SIG_NAME P3V3_OCP_SFF_EN_R
J 0
(2190 11835);
DISPLAY 0.638298 (2190 11835);
WIRE 16 -1 (9900 10900)(9900 10725);
FORCEPROP 2 LAST SIG_NAME HP_LVC3_OCP_V3_1_P12V_PWRGD
J 0
(9615 10735);
DISPLAY 0.574468 (9615 10735);
WIRE 16 -1 (9900 10725)(10325 10725);
WIRE 16 -1 (9225 10725)(9900 10725);
WIRE 16 -1 (3225 12225)(2150 12225);
FORCEPROP 2 LAST SIG_NAME HP_LVC3_OCP_V3_1_P12V_PWRGD
J 0
(2190 12235);
DISPLAY 0.680851 (2190 12235);
WIRE 16 -1 (7225 10425)(6875 10425);
FORCEPROP 2 LAST SIG_NAME P12V_OCP_CB_1
J 0
(6790 10435);
DISPLAY 0.574468 (6790 10435);
FORCEPROP 2 LASTPROP $XRERR UNIQUE?
J 0
(6550 10435);
DISPLAY 0.638298 (6550 10435);
PAINT MONO (6550 10435);
DISPLAY INVISIBLE (6550 10435);
WIRE 16 -1 (6875 10425)(6875 10325);
WIRE 16 2175 (8975 10600)(9700 10600);
WIRE 16 2175 (8975 10600)(8975 10200);
WIRE 16 2175 (9700 10600)(9700 10200);
WIRE 16 2175 (8975 10200)(9700 10200);
WIRE 16 -1 (8025 10625)(9475 10625);
FORCEPROP 2 LAST SIG_NAME P12V_OCP_FAULT_1
J 0
(8090 10635);
DISPLAY 0.574468 (8090 10635);
FORCEPROP 2 LASTPROP $XRERR UNIQUE?
J 0
(7850 10635);
DISPLAY 0.638298 (7850 10635);
PAINT MONO (7850 10635);
DISPLAY INVISIBLE (7850 10635);
WIRE 16 -1 (9475 10625)(9475 10900);
WIRE 16 -1 (8025 10925)(8332 10925);
WIRE 16 -1 (8332 10925)(8332 10975);
WIRE 16 -1 (8332 10975)(8332 11025);
WIRE 16 -1 (8025 10975)(8332 10975);
WIRE 16 -1 (8332 11025)(8332 11075);
WIRE 16 -1 (8332 11025)(8025 11025);
WIRE 16 -1 (8332 11075)(8332 11125);
WIRE 16 -1 (8025 11075)(8332 11075);
WIRE 16 -1 (8332 11125)(8332 11175);
WIRE 16 -1 (8025 11125)(8332 11125);
WIRE 16 -1 (8332 11175)(8332 11225);
WIRE 16 -1 (8025 11175)(8332 11175);
WIRE 16 -1 (8332 11225)(8400 11225);
WIRE 16 -1 (8025 11225)(8332 11225);
WIRE 16 -1 (8400 11225)(8545 11225);
WIRE 16 -1 (8400 11150)(8400 11225);
WIRE 16 -1 (8545 11875)(8545 11225);
WIRE 16 -1 (8545 11225)(8725 11225);
WIRE 16 -1 (8725 11225)(8725 11150);
WIRE 16 -1 (8545 11875)(8825 11875);
WIRE 16 -1 (9300 11875)(8825 11875);
WIRE 16 -1 (8825 11875)(8825 11825);
WIRE 16 -1 (9725 11875)(9300 11875);
WIRE 16 -1 (9300 11775)(9300 11875);
WIRE 16 -1 (10125 11875)(9725 11875);
WIRE 16 -1 (9725 11875)(9725 11775);
WIRE 16 -1 (10125 11925)(10125 11875);
WIRE 16 -1 (10125 11775)(10125 11875);
WIRE 16 -1 (9425 12775)(10225 12775);
FORCEPROP 2 LAST SIG_NAME OCP_V3_1_P3V3_PWRGD
J 0
(9690 12785);
DISPLAY 0.574468 (9690 12785);
WIRE 16 -1 (10225 12775)(10325 12775);
WIRE 16 -1 (10225 12950)(10225 12775);
DOT 1 (3625 10525);
DOT 1 (8332 11125);
DOT 1 (5450 11185);
DOT 1 (9300 11875);
DOT 1 (6350 10725);
DOT 1 (8400 11225);
DOT 1 (7125 10975);
DOT 1 (6025 10625);
DOT 1 (6025 10825);
DOT 1 (6875 10025);
DOT 1 (8725 10825);
DOT 1 (8475 10525);
DOT 1 (9900 10725);
DOT 1 (8400 10825);
DOT 1 (9650 11225);
DOT 1 (8332 11175);
DOT 1 (8425 12225);
DOT 1 (7125 11025);
DOT 1 (3550 11825);
DOT 1 (3650 11825);
DOT 1 (8675 12875);
DOT 1 (8557 13025);
DOT 1 (8557 13125);
DOT 1 (8557 13175);
DOT 1 (9550 13850);
DOT 1 (8557 13225);
DOT 1 (8557 13075);
DOT 1 (8675 13275);
DOT 1 (7125 11125);
DOT 1 (8200 8675);
DOT 1 (8350 9525);
DOT 1 (6525 8900);
DOT 1 (5725 8600);
DOT 1 (5950 9450);
DOT 1 (8150 10175);
DOT 1 (9725 11875);
DOT 1 (8375 12225);
DOT 1 (10125 13850);
DOT 1 (10125 13475);
DOT 1 (9050 13850);
DOT 1 (10125 11875);
DOT 1 (10125 11500);
DOT 1 (9725 11500);
DOT 1 (9300 11500);
DOT 1 (8825 11875);
DOT 1 (8575 12225);
DOT 1 (8475 12225);
DOT 1 (8332 11075);
DOT 1 (8332 10975);
DOT 1 (8350 10175);
DOT 1 (8200 10175);
DOT 1 (8350 8900);
DOT 1 (7350 13075);
DOT 1 (6250 13725);
DOT 1 (6250 12675);
DOT 1 (6250 12375);
DOT 1 (5900 13725);
DOT 1 (7125 11075);
DOT 1 (7100 12075);
DOT 1 (6350 11675);
DOT 1 (6350 11250);
DOT 1 (6025 11675);
DOT 1 (5725 9400);
DOT 1 (5725 8900);
DOT 1 (5950 8550);
DOT 1 (4125 8500);
DOT 1 (3900 9075);
DOT 1 (3900 8600);
DOT 1 (8250 10175);
DOT 1 (4225 9400);
DOT 1 (3950 9500);
DOT 1 (4150 9975);
DOT 1 (6025 10325);
DOT 1 (3325 10225);
DOT 1 (3025 10225);
DOT 1 (10225 12775);
DOT 1 (8770 13275);
DOT 1 (8925 12875);
DOT 1 (8557 13275);
DOT 1 (9875 13250);
DOT 1 (7350 13275);
DOT 1 (7350 13225);
DOT 1 (6575 13725);
DOT 1 (7350 13175);
DOT 1 (6575 13300);
DOT 1 (7350 13025);
DOT 1 (6250 12875);
DOT 1 (6575 12775);
DOT 1 (4225 12200);
DOT 1 (7350 13125);
DOT 1 (9550 13475);
DOT 1 (5675 11675);
DOT 1 (8332 11025);
DOT 1 (3550 12225);
DOT 1 (5450 11675);
DOT 1 (7125 11225);
DOT 1 (8332 11225);
DOT 1 (7125 11175);
DOT 1 (8545 11225);
DOT 1 (8925 10525);
FORCENOTE
FROM PRSNT BUFFER
(1750 10525) 0;
DISPLAY LEFT (1750 10525);
DISPLAY 1.021277 (1750 10525);
FORCENOTE
FROM PRSNT BUFFER
(1850 12750) 0;
DISPLAY LEFT (1850 12750);
DISPLAY 1.021277 (1850 12750);
FORCENOTE
UVP: 10.17V
(5450 10575) 0;
DISPLAY LEFT (5450 10575);
DISPLAY 1.021277 (5450 10575);
PAINT WHITE (5450 10575);
FORCENOTE
OVP: 14.91V
(5450 10500) 0;
DISPLAY LEFT (5450 10500);
DISPLAY 1.021277 (5450 10500);
PAINT WHITE (5450 10500);
FORCENOTE
OCP=IMAX*1.3=8.58A
(1775 13650) 0;
DISPLAY LEFT (1775 13650);
DISPLAY 1.021277 (1775 13650);
FORCENOTE
IMAX=6.6A
(1775 13725) 0;
DISPLAY LEFT (1775 13725);
DISPLAY 1.021277 (1775 13725);
FORCENOTE
P12V_OCP_V3
(1775 13800) 0;
DISPLAY LEFT (1775 13800);
DISPLAY 1.021277 (1775 13800);
FORCENOTE
P3V3_OCP_V3
(1775 14200) 0;
DISPLAY LEFT (1775 14200);
DISPLAY 0.936170 (1775 14200);
FORCENOTE
OCP=IMAX*1.3=1.43A
(1775 14050) 0;
DISPLAY LEFT (1775 14050);
DISPLAY 0.936170 (1775 14050);
FORCENOTE
DESIGN SPECIFICATION
(1775 14300) 0;
DISPLAY LEFT (1775 14300);
DISPLAY 1.170213 (1775 14300);
FORCENOTE
IMAX=1.1A
(1775 14125) 0;
DISPLAY LEFT (1775 14125);
DISPLAY 0.936170 (1775 14125);
FORCENOTE
FROM OCP_12V_PG
(1875 12325) 0;
DISPLAY LEFT (1875 12325);
DISPLAY 1.021277 (1875 12325);
FORCENOTE
FROM CPLD
(1750 10325) 0;
DISPLAY LEFT (1750 10325);
DISPLAY 1.021277 (1750 10325);
FORCENOTE
FROM CPLD
(1900 11900) 0;
DISPLAY LEFT (1900 11900);
DISPLAY 1.021277 (1900 11900);
FORCENOTE
START UP TIME:8.21MS
(9550 10600) 0;
DISPLAY LEFT (9550 10600);
DISPLAY 1.021277 (9550 10600);
PAINT WHITE (9550 10600);
FORCENOTE
OVP: 3.89V
(5725 12500) 0;
DISPLAY LEFT (5725 12500);
DISPLAY 1.021277 (5725 12500);
PAINT WHITE (5725 12500);
FORCENOTE
UVP: 2.63V
(5725 12575) 0;
DISPLAY LEFT (5725 12575);
DISPLAY 1.021277 (5725 12575);
PAINT WHITE (5725 12575);
FORCENOTE
VIMON(MAX)= 1.679V @ IOUT=9.03A
(7200 9825) 0;
DISPLAY LEFT (7200 9825);
DISPLAY 1.021277 (7200 9825);
PAINT WHITE (7200 9825);
FORCENOTE
VIMON(MAX)= 1.594V @ IOUT=1.6A
(7275 11950) 0;
DISPLAY LEFT (7275 11950);
DISPLAY 1.021277 (7275 11950);
PAINT WHITE (7275 11950);
FORCENOTE
START UP TIME:3.94MS
(9150 12550) 0;
DISPLAY LEFT (9150 12550);
DISPLAY 1.021277 (9150 12550);
PAINT WHITE (9150 12550);
QUIT
